FILE_TYPE = MACRO_DRAWING;
SET COLOR_WIRE YELLOW;
SET COLOR_PROP ORANGE;
SET COLOR_DOT WHITE;
SET COLOR_ARC YELLOW;
SET COLOR_BODY GREEN;
SET COLOR_NOTE PURPLE;
SET PROP_DISPLAY VALUE;
SET PAGE_NUMBER P185;
FORCEADD MOSFET_N..1
(-7825 1525);
FORCEPROP 1 LAST LOCATION PQ15
J 0
(-7700 1525);
DISPLAY 0.489362 (-7700 1525);
PAINT SKYBLUE (-7700 1525);
FORCEPROP 0 LAST $SEC 1
J 0
(-7700 1550);
DISPLAY 0.680851 (-7700 1550);
PAINT MONO (-7700 1550);
DISPLAY INVISIBLE (-7700 1550);
FORCEPROP 0 LAST CDS_SEC 1
J 0
(-7700 1550);
DISPLAY 1.021277 (-7700 1550);
DISPLAY INVISIBLE (-7700 1550);
FORCEPROP 1 LASTPIN (-7775 1625) $PN D
R 1
J 0
(-7775 1618);
DISPLAY 0.489362 (-7775 1618);
PAINT MONO (-7775 1618);
FORCEPROP 1 LASTPIN (-7925 1425) $PN G
J 2
(-7915 1428);
DISPLAY 0.489362 (-7915 1428);
PAINT MONO (-7915 1428);
FORCEPROP 1 LASTPIN (-7775 1325) $PN S
R 1
J 2
(-7775 1338);
DISPLAY 0.489362 (-7775 1338);
PAINT MONO (-7775 1338);
FORCEPROP 1 LAST MATERIAL IC
J 0
(-7700 1375);
DISPLAY 0.489362 (-7700 1375);
PAINT SKYBLUE (-7700 1375);
FORCEPROP 1 LAST VALUE BSS138K
J 0
(-7700 1475);
DISPLAY 0.489362 (-7700 1475);
PAINT SKYBLUE (-7700 1475);
FORCEPROP 1 LAST PART_NUMBER BAM138K0000
J 0
(-7700 1425);
DISPLAY 0.489362 (-7700 1425);
PAINT SKYBLUE (-7700 1425);
FORCEPROP 0 LAST MANUF_PN BSS138K
J 0
(-7725 1325);
DISPLAY 1.021277 (-7725 1325);
DISPLAY INVISIBLE (-7725 1325);
FORCEPROP 1 LAST CDS_LMAN_SYM_OUTLINE -50,50,100,-150
J 0
(-7825 1525);
DISPLAY 0.468085 (-7825 1525);
PAINT GREEN (-7825 1525);
DISPLAY INVISIBLE (-7825 1525);
FORCEPROP 2 LAST CDS_LIB pure_quanta
J 0
(-7825 1525);
DISPLAY INVISIBLE (-7825 1525);
FORCEPROP 0 LAST PATH I1
J 0
(-7650 1350);
DISPLAY 1.021277 (-7650 1350);
DISPLAY INVISIBLE (-7650 1350);
FORCEPROP 1 LAST PACK_TYPE SMLF
J 0
(-7800 1275);
DISPLAY 0.723404 (-7800 1275);
PAINT SKYBLUE (-7800 1275);
DISPLAY INVISIBLE (-7800 1275);
FORCEADD UNIVERSAL_GND..1
(-2900 5875);
FORCEPROP 3 LASTPIN (-2900 5925) SIG_NAME GND\g
J 0
(-2890 5935);
DISPLAY 0.659574 (-2890 5935);
PAINT MONO (-2890 5935);
DISPLAY INVISIBLE (-2890 5935);
FORCEPROP 2 LAST CDS_LIB pure_quanta_power
J 0
(-2900 5875);
DISPLAY INVISIBLE (-2900 5875);
FORCEPROP 1 LAST PATH I10
J 0
(-2825 5875);
DISPLAY 0.872340 (-2825 5875);
PAINT AQUA (-2825 5875);
DISPLAY INVISIBLE (-2825 5875);
FORCEPROP 1 LAST HDL_POWER GND
J 1
(-2875 5800);
DISPLAY 0.872340 (-2875 5800);
PAINT GREEN (-2875 5800);
DISPLAY INVISIBLE (-2875 5800);
FORCEADD Q_CAP..1
(-5300 475);
FORCEPROP 1 LAST LOCATION PC6
J 0
(-5250 575);
DISPLAY 0.489362 (-5250 575);
PAINT SKYBLUE (-5250 575);
FORCEPROP 2 LAST SEC 1
J 0
(-5250 675);
DISPLAY 0.680851 (-5250 675);
PAINT MONO (-5250 675);
DISPLAY INVISIBLE (-5250 675);
FORCEPROP 1 LASTPIN (-5300 575) $PN 1
J 0
(-5290 555);
DISPLAY 0.489362 (-5290 555);
PAINT MONO (-5290 555);
FORCEPROP 1 LASTPIN (-5300 375) $PN 2
J 0
(-5290 355);
DISPLAY 0.489362 (-5290 355);
PAINT MONO (-5290 355);
FORCEPROP 1 LAST MATERIAL X7R
J 0
(-5250 375);
DISPLAY 0.489362 (-5250 375);
PAINT SKYBLUE (-5250 375);
FORCEPROP 1 LAST TOLERANCE 10%
J 0
(-5250 425);
DISPLAY 0.489362 (-5250 425);
PAINT SKYBLUE (-5250 425);
FORCEPROP 1 LAST VALUE 0.1UF
J 0
(-5250 525);
DISPLAY 0.489362 (-5250 525);
PAINT SKYBLUE (-5250 525);
FORCEPROP 1 LAST PART_NUMBER CH4104K1B00
J 0
(-5250 325);
DISPLAY 0.489362 (-5250 325);
PAINT SKYBLUE (-5250 325);
FORCEPROP 1 LAST VOLTAGE 25V
J 0
(-5250 475);
DISPLAY 0.489362 (-5250 475);
PAINT SKYBLUE (-5250 475);
FORCEPROP 1 LAST PACK_TYPE 0402
J 0
(-5250 275);
DISPLAY 0.489362 (-5250 275);
PAINT SKYBLUE (-5250 275);
FORCEPROP 2 LAST CDS_LIB pure_quanta
J 0
(-5300 475);
DISPLAY INVISIBLE (-5300 475);
FORCEPROP 2 LAST SEC_TYPE 0402
J 0
(-5250 675);
DISPLAY 1.021277 (-5250 675);
DISPLAY INVISIBLE (-5250 675);
FORCEPROP 1 LAST PATH I100
J 0
(-5250 625);
DISPLAY 0.978723 (-5250 625);
PAINT WHITE (-5250 625);
DISPLAY INVISIBLE (-5250 625);
FORCEADD Q_RES..1
(-5950 650);
FORCEPROP 1 LAST LOCATION PR181
J 0
(-5975 700);
DISPLAY 0.489362 (-5975 700);
PAINT SKYBLUE (-5975 700);
FORCEPROP 0 LAST $SEC 1
J 0
(-6000 750);
DISPLAY 0.680851 (-6000 750);
PAINT MONO (-6000 750);
DISPLAY INVISIBLE (-6000 750);
FORCEPROP 0 LAST CDS_SEC 1
J 0
(-6000 750);
DISPLAY 1.021277 (-6000 750);
DISPLAY INVISIBLE (-6000 750);
FORCEPROP 1 LASTPIN (-6050 650) $PN 1
J 0
(-6038 662);
DISPLAY 0.489362 (-6038 662);
PAINT MONO (-6038 662);
FORCEPROP 1 LASTPIN (-5850 650) $PN 2
J 0
(-5888 662);
DISPLAY 0.489362 (-5888 662);
PAINT MONO (-5888 662);
FORCEPROP 1 LAST MATERIAL CHIP
J 0
(-6200 575);
DISPLAY 0.489362 (-6200 575);
PAINT SKYBLUE (-6200 575);
FORCEPROP 1 LAST PART_NUMBER CS00002JB38
J 0
(-6200 600);
DISPLAY 0.489362 (-6200 600);
PAINT SKYBLUE (-6200 600);
FORCEPROP 1 LAST WATTAGE 1/16W
J 0
(-5850 600);
DISPLAY 0.489362 (-5850 600);
PAINT SKYBLUE (-5850 600);
FORCEPROP 1 LAST TOLERANCE 5%
J 0
(-5825 675);
DISPLAY 0.489362 (-5825 675);
PAINT SKYBLUE (-5825 675);
FORCEPROP 1 LAST VALUE 0
J 2
(-6075 675);
DISPLAY 0.489362 (-6075 675);
PAINT SKYBLUE (-6075 675);
FORCEPROP 1 LAST PACK_TYPE 0402LF
J 0
(-5850 575);
DISPLAY 0.489362 (-5850 575);
PAINT SKYBLUE (-5850 575);
FORCEPROP 2 LAST CDS_LIB pure_quanta
J 0
(-5950 650);
DISPLAY INVISIBLE (-5950 650);
FORCEPROP 1 LAST PATH I101
J 0
(-6000 800);
DISPLAY 0.978723 (-6000 800);
PAINT WHITE (-6000 800);
DISPLAY INVISIBLE (-6000 800);
FORCEADD UNIVERSAL_GND..1
(-5300 250);
FORCEPROP 3 LASTPIN (-5300 300) SIG_NAME GND\g
J 0
(-5290 310);
DISPLAY 0.659574 (-5290 310);
PAINT MONO (-5290 310);
DISPLAY INVISIBLE (-5290 310);
FORCEPROP 2 LAST CDS_LIB pure_quanta_power
J 0
(-5300 250);
DISPLAY INVISIBLE (-5300 250);
FORCEPROP 1 LAST PATH I102
J 0
(-5225 250);
DISPLAY 0.872340 (-5225 250);
PAINT AQUA (-5225 250);
DISPLAY INVISIBLE (-5225 250);
FORCEPROP 1 LAST HDL_POWER GND
J 1
(-5275 175);
DISPLAY 0.872340 (-5275 175);
PAINT GREEN (-5275 175);
DISPLAY INVISIBLE (-5275 175);
FORCEADD VCC_CORE..1
(-6200 725);
FORCEPROP 3 LASTPIN (-6200 675) SIG_NAME P12V_STBY\g
J 0
(-6190 685);
DISPLAY 0.659574 (-6190 685);
PAINT MONO (-6190 685);
DISPLAY INVISIBLE (-6190 685);
FORCEPROP 1 LAST HDL_POWER P12V_STBY
J 1
(-6200 775);
DISPLAY 0.489362 (-6200 775);
PAINT GREEN (-6200 775);
FORCEPROP 2 LAST CDS_LIB pure_quanta_power
J 0
(-6200 725);
DISPLAY INVISIBLE (-6200 725);
FORCEPROP 1 LAST PATH I103
J 0
(-6150 750);
DISPLAY 0.872340 (-6150 750);
PAINT AQUA (-6150 750);
DISPLAY INVISIBLE (-6150 750);
FORCEADD Q_RES..1
(-7250 825);
FORCEPROP 1 LAST LOCATION PR157
J 0
(-7300 875);
DISPLAY 0.489362 (-7300 875);
PAINT SKYBLUE (-7300 875);
FORCEPROP 0 LAST $SEC 1
J 0
(-7300 925);
DISPLAY 0.680851 (-7300 925);
PAINT MONO (-7300 925);
DISPLAY INVISIBLE (-7300 925);
FORCEPROP 0 LAST CDS_SEC 1
J 0
(-7300 925);
DISPLAY 1.021277 (-7300 925);
DISPLAY INVISIBLE (-7300 925);
FORCEPROP 1 LASTPIN (-7350 825) $PN 1
J 0
(-7338 837);
DISPLAY 0.489362 (-7338 837);
PAINT MONO (-7338 837);
FORCEPROP 1 LASTPIN (-7150 825) $PN 2
J 0
(-7188 837);
DISPLAY 0.489362 (-7188 837);
PAINT MONO (-7188 837);
FORCEPROP 1 LAST WATTAGE 1/16W
J 0
(-7125 775);
DISPLAY 0.489362 (-7125 775);
PAINT SKYBLUE (-7125 775);
FORCEPROP 1 LAST MATERIAL CHIP
J 0
(-7550 750);
DISPLAY 0.489362 (-7550 750);
PAINT SKYBLUE (-7550 750);
FORCEPROP 1 LAST TOLERANCE 1%
J 0
(-7100 850);
DISPLAY 0.489362 (-7100 850);
PAINT SKYBLUE (-7100 850);
FORCEPROP 1 LAST VALUE 40.2K
J 2
(-7400 850);
DISPLAY 0.489362 (-7400 850);
PAINT SKYBLUE (-7400 850);
FORCEPROP 1 LAST PART_NUMBER TMP_QCS34022FB15
J 0
(-7550 775);
DISPLAY 0.489362 (-7550 775);
PAINT SKYBLUE (-7550 775);
FORCEPROP 1 LAST PACK_TYPE 0402LF
J 0
(-7125 750);
DISPLAY 0.489362 (-7125 750);
PAINT SKYBLUE (-7125 750);
FORCEPROP 2 LAST CDS_LIB pure_quanta
J 0
(-7250 825);
DISPLAY INVISIBLE (-7250 825);
FORCEPROP 1 LAST PATH I104
J 0
(-7300 975);
DISPLAY 0.978723 (-7300 975);
PAINT WHITE (-7300 975);
DISPLAY INVISIBLE (-7300 975);
FORCEADD Q_RES..2
(-6950 650);
FORCEPROP 1 LAST LOCATION PR4
J 0
(-6900 750);
DISPLAY 0.489362 (-6900 750);
PAINT SKYBLUE (-6900 750);
FORCEPROP 2 LAST SEC 1
J 0
(-6900 875);
DISPLAY 0.680851 (-6900 875);
PAINT MONO (-6900 875);
DISPLAY INVISIBLE (-6900 875);
FORCEPROP 1 LASTPIN (-6950 750) $PN 1
J 0
(-6945 712);
DISPLAY 0.489362 (-6945 712);
PAINT MONO (-6945 712);
FORCEPROP 1 LASTPIN (-6950 550) $PN 2
J 0
(-6945 560);
DISPLAY 0.489362 (-6945 560);
PAINT MONO (-6945 560);
FORCEPROP 1 LAST WATTAGE 1/16W
J 0
(-6900 600);
DISPLAY 0.489362 (-6900 600);
PAINT SKYBLUE (-6900 600);
FORCEPROP 1 LAST MATERIAL CHIP
J 0
(-6900 550);
DISPLAY 0.489362 (-6900 550);
PAINT SKYBLUE (-6900 550);
FORCEPROP 1 LAST TOLERANCE 1%
J 0
(-6900 650);
DISPLAY 0.489362 (-6900 650);
PAINT SKYBLUE (-6900 650);
FORCEPROP 1 LAST VALUE 10K
J 0
(-6900 700);
DISPLAY 0.489362 (-6900 700);
PAINT SKYBLUE (-6900 700);
FORCEPROP 1 LAST PART_NUMBER TMP_QCS31002FB26
J 0
(-6900 500);
DISPLAY 0.489362 (-6900 500);
PAINT SKYBLUE (-6900 500);
FORCEPROP 1 LAST PACK_TYPE 0402LF
J 0
(-6900 450);
DISPLAY 0.489362 (-6900 450);
PAINT SKYBLUE (-6900 450);
FORCEPROP 2 LAST SEC_TYPE 0402LF
J 0
(-6900 875);
DISPLAY 1.021277 (-6900 875);
DISPLAY INVISIBLE (-6900 875);
FORCEPROP 2 LAST CDS_LIB pure_quanta
J 0
(-6950 650);
DISPLAY INVISIBLE (-6950 650);
FORCEPROP 1 LAST PATH I105
J 0
(-6900 825);
DISPLAY 0.978723 (-6900 825);
PAINT WHITE (-6900 825);
DISPLAY INVISIBLE (-6900 825);
FORCEADD UNIVERSAL_GND..1
(-6950 400);
FORCEPROP 3 LASTPIN (-6950 450) SIG_NAME GND\g
J 0
(-6940 460);
DISPLAY 0.659574 (-6940 460);
PAINT MONO (-6940 460);
DISPLAY INVISIBLE (-6940 460);
FORCEPROP 2 LAST CDS_LIB pure_quanta_power
J 0
(-6950 400);
DISPLAY INVISIBLE (-6950 400);
FORCEPROP 1 LAST PATH I107
J 0
(-6875 400);
DISPLAY 0.872340 (-6875 400);
PAINT AQUA (-6875 400);
DISPLAY INVISIBLE (-6875 400);
FORCEPROP 1 LAST HDL_POWER GND
J 1
(-6925 325);
DISPLAY 0.872340 (-6925 325);
PAINT GREEN (-6925 325);
DISPLAY INVISIBLE (-6925 325);
FORCEADD UNIVERSAL_GND..1
(-6475 400);
FORCEPROP 3 LASTPIN (-6475 450) SIG_NAME GND\g
J 0
(-6465 460);
DISPLAY 0.659574 (-6465 460);
PAINT MONO (-6465 460);
DISPLAY INVISIBLE (-6465 460);
FORCEPROP 2 LAST CDS_LIB pure_quanta_power
J 0
(-6475 400);
DISPLAY INVISIBLE (-6475 400);
FORCEPROP 1 LAST PATH I108
J 0
(-6400 400);
DISPLAY 0.872340 (-6400 400);
PAINT AQUA (-6400 400);
DISPLAY INVISIBLE (-6400 400);
FORCEPROP 1 LAST HDL_POWER GND
J 1
(-6450 325);
DISPLAY 0.872340 (-6450 325);
PAINT GREEN (-6450 325);
DISPLAY INVISIBLE (-6450 325);
FORCEADD VCC_CORE..1
(-7550 950);
FORCEPROP 3 LASTPIN (-7550 900) SIG_NAME P5V_STBY\g
J 0
(-7540 910);
DISPLAY 0.659574 (-7540 910);
PAINT MONO (-7540 910);
DISPLAY INVISIBLE (-7540 910);
FORCEPROP 1 LAST HDL_POWER P5V_STBY
J 1
(-7550 1000);
DISPLAY 0.489362 (-7550 1000);
PAINT GREEN (-7550 1000);
FORCEPROP 2 LAST CDS_LIB pure_quanta_power
J 0
(-7550 950);
DISPLAY INVISIBLE (-7550 950);
FORCEPROP 1 LAST PATH I109
J 0
(-7500 975);
DISPLAY 0.872340 (-7500 975);
PAINT AQUA (-7500 975);
DISPLAY INVISIBLE (-7500 975);
FORCEADD OFFPAGE..2
R 2
(-7150 1000);
FORCEPROP 2 LAST $XR0 79 
J 0
(-7404 1000);
DISPLAY 0.638298 (-7404 1000);
PAINT MONO (-7404 1000);
FORCEPROP 2 LAST CDS_LIB standard
J 0
(-7150 1000);
DISPLAY INVISIBLE (-7150 1000);
FORCEPROP 1 LAST OFFPAGE TRUE
J 2
(-7475 875);
DISPLAY 0.872340 (-7475 875);
PAINT GREEN (-7475 875);
DISPLAY INVISIBLE (-7475 875);
FORCEPROP 1 LAST COMMENT_BODY TRUE
J 2
(-7105 905);
DISPLAY 0.872340 (-7105 905);
PAINT GREEN (-7105 905);
DISPLAY INVISIBLE (-7105 905);
FORCEPROP 2 LAST PATH I110
J 0
(-7100 1075);
DISPLAY 1.021277 (-7100 1075);
DISPLAY INVISIBLE (-7100 1075);
FORCEADD VCC_CORE..1
(-6600 1400);
FORCEPROP 3 LASTPIN (-6600 1350) SIG_NAME P3V3_STBY\g
J 0
(-6590 1360);
DISPLAY 0.659574 (-6590 1360);
PAINT MONO (-6590 1360);
DISPLAY INVISIBLE (-6590 1360);
FORCEPROP 1 LAST HDL_POWER P3V3_STBY
J 1
(-6600 1450);
DISPLAY 0.489362 (-6600 1450);
PAINT GREEN (-6600 1450);
FORCEPROP 2 LAST CDS_LIB pure_quanta_power
J 0
(-6600 1400);
DISPLAY INVISIBLE (-6600 1400);
FORCEPROP 1 LAST PATH I111
J 0
(-6550 1425);
DISPLAY 0.872340 (-6550 1425);
PAINT AQUA (-6550 1425);
DISPLAY INVISIBLE (-6550 1425);
FORCEADD Q_RES..1
(-6325 1250);
FORCEPROP 1 LAST LOCATION PR165
J 0
(-6375 1300);
DISPLAY 0.489362 (-6375 1300);
PAINT SKYBLUE (-6375 1300);
FORCEPROP 0 LAST $SEC 1
J 0
(-6375 1350);
DISPLAY 0.680851 (-6375 1350);
PAINT MONO (-6375 1350);
DISPLAY INVISIBLE (-6375 1350);
FORCEPROP 0 LAST CDS_SEC 1
J 0
(-6375 1350);
DISPLAY 1.021277 (-6375 1350);
DISPLAY INVISIBLE (-6375 1350);
FORCEPROP 1 LASTPIN (-6425 1250) $PN 1
J 0
(-6413 1262);
DISPLAY 0.489362 (-6413 1262);
PAINT MONO (-6413 1262);
FORCEPROP 1 LASTPIN (-6225 1250) $PN 2
J 0
(-6263 1262);
DISPLAY 0.489362 (-6263 1262);
PAINT MONO (-6263 1262);
FORCEPROP 1 LAST MATERIAL CHIP
J 0
(-6650 1150);
DISPLAY 0.489362 (-6650 1150);
PAINT SKYBLUE (-6650 1150);
FORCEPROP 1 LAST WATTAGE 1/16W
J 0
(-6225 1200);
DISPLAY 0.489362 (-6225 1200);
PAINT SKYBLUE (-6225 1200);
FORCEPROP 1 LAST TOLERANCE 1%
J 0
(-6225 1275);
DISPLAY 0.489362 (-6225 1275);
PAINT SKYBLUE (-6225 1275);
FORCEPROP 1 LAST VALUE 1K
J 2
(-6475 1275);
DISPLAY 0.489362 (-6475 1275);
PAINT SKYBLUE (-6475 1275);
FORCEPROP 1 LAST PART_NUMBER TMP_QCS21002FB24
J 0
(-6650 1200);
DISPLAY 0.489362 (-6650 1200);
PAINT SKYBLUE (-6650 1200);
FORCEPROP 1 LAST PACK_TYPE 0402LF
J 0
(-6225 1150);
DISPLAY 0.489362 (-6225 1150);
PAINT SKYBLUE (-6225 1150);
FORCEPROP 2 LAST CDS_LIB pure_quanta
J 0
(-6325 1250);
DISPLAY INVISIBLE (-6325 1250);
FORCEPROP 1 LAST PATH I112
J 0
(-6375 1400);
DISPLAY 0.978723 (-6375 1400);
PAINT WHITE (-6375 1400);
DISPLAY INVISIBLE (-6375 1400);
FORCEADD Q_RES..1
(-6325 1000);
FORCEPROP 1 LAST LOCATION PR166
J 0
(-6375 1050);
DISPLAY 0.489362 (-6375 1050);
PAINT SKYBLUE (-6375 1050);
FORCEPROP 0 LAST $SEC 1
J 0
(-6375 1100);
DISPLAY 0.680851 (-6375 1100);
PAINT MONO (-6375 1100);
DISPLAY INVISIBLE (-6375 1100);
FORCEPROP 0 LAST CDS_SEC 1
J 0
(-6375 1100);
DISPLAY 1.021277 (-6375 1100);
DISPLAY INVISIBLE (-6375 1100);
FORCEPROP 1 LASTPIN (-6425 1000) $PN 1
J 0
(-6413 1012);
DISPLAY 0.489362 (-6413 1012);
PAINT MONO (-6413 1012);
FORCEPROP 1 LASTPIN (-6225 1000) $PN 2
J 0
(-6263 1012);
DISPLAY 0.489362 (-6263 1012);
PAINT MONO (-6263 1012);
FORCEPROP 1 LAST PACK_TYPE 0402LF
J 0
(-6225 925);
DISPLAY 0.489362 (-6225 925);
PAINT SKYBLUE (-6225 925);
FORCEPROP 1 LAST WATTAGE 1/16W
J 0
(-6225 950);
DISPLAY 0.489362 (-6225 950);
PAINT SKYBLUE (-6225 950);
FORCEPROP 1 LAST MATERIAL CHIP
J 0
(-6575 925);
DISPLAY 0.489362 (-6575 925);
PAINT SKYBLUE (-6575 925);
FORCEPROP 1 LAST TOLERANCE 5%
J 0
(-6200 1025);
DISPLAY 0.489362 (-6200 1025);
PAINT SKYBLUE (-6200 1025);
FORCEPROP 1 LAST VALUE 0
J 2
(-6450 1025);
DISPLAY 0.489362 (-6450 1025);
PAINT SKYBLUE (-6450 1025);
FORCEPROP 1 LAST PART_NUMBER CS00002JB38
J 0
(-6575 950);
DISPLAY 0.489362 (-6575 950);
PAINT SKYBLUE (-6575 950);
FORCEPROP 2 LAST CDS_LIB pure_quanta
J 0
(-6325 1000);
DISPLAY INVISIBLE (-6325 1000);
FORCEPROP 1 LAST PATH I113
J 0
(-6375 1150);
DISPLAY 0.978723 (-6375 1150);
PAINT WHITE (-6375 1150);
DISPLAY INVISIBLE (-6375 1150);
FORCEADD Q_CAP..2
(-5650 1250);
FORCEPROP 1 LAST LOCATION PC246
J 1
(-5650 1325);
DISPLAY 0.489362 (-5650 1325);
PAINT SKYBLUE (-5650 1325);
FORCEPROP 0 LAST $SEC 1
J 0
(-5650 1400);
DISPLAY 0.680851 (-5650 1400);
PAINT MONO (-5650 1400);
DISPLAY INVISIBLE (-5650 1400);
FORCEPROP 0 LAST CDS_SEC 1
J 0
(-5650 1400);
DISPLAY 1.021277 (-5650 1400);
DISPLAY INVISIBLE (-5650 1400);
FORCEPROP 1 LASTPIN (-5750 1250) $PN 1
J 0
(-5760 1265);
DISPLAY 0.489362 (-5760 1265);
PAINT MONO (-5760 1265);
FORCEPROP 1 LASTPIN (-5550 1250) $PN 2
J 0
(-5565 1265);
DISPLAY 0.489362 (-5565 1265);
PAINT MONO (-5565 1265);
FORCEPROP 1 LAST MATERIAL EMPTY
J 0
(-5925 1125);
DISPLAY 0.489362 (-5925 1125);
PAINT RED (-5925 1125);
FORCEPROP 1 LAST TOLERANCE 5%
J 0
(-5525 1125);
DISPLAY 0.489362 (-5525 1125);
PAINT SKYBLUE (-5525 1125);
FORCEPROP 1 LAST VALUE 1000PF
J 2
(-5775 1300);
DISPLAY 0.489362 (-5775 1300);
PAINT SKYBLUE (-5775 1300);
FORCEPROP 1 LAST PART_NUMBER TMP_QCH21006JB10
J 1
(-5800 1175);
DISPLAY 0.489362 (-5800 1175);
PAINT SKYBLUE (-5800 1175);
FORCEPROP 1 LAST VOLTAGE 50V
J 0
(-5525 1300);
DISPLAY 0.489362 (-5525 1300);
PAINT SKYBLUE (-5525 1300);
FORCEPROP 1 LAST PACK_TYPE 0402
J 0
(-5525 1175);
DISPLAY 0.489362 (-5525 1175);
PAINT SKYBLUE (-5525 1175);
FORCEPROP 2 LAST CDS_LIB pure_quanta
J 0
(-5650 1250);
DISPLAY INVISIBLE (-5650 1250);
FORCEPROP 1 LAST PATH I114
J 0
(-5650 1450);
DISPLAY 0.978723 (-5650 1450);
PAINT WHITE (-5650 1450);
DISPLAY INVISIBLE (-5650 1450);
FORCEADD UNIVERSAL_GND..1
(-5325 1125);
FORCEPROP 3 LASTPIN (-5325 1175) SIG_NAME GND\g
J 0
(-5315 1185);
DISPLAY 0.659574 (-5315 1185);
PAINT MONO (-5315 1185);
DISPLAY INVISIBLE (-5315 1185);
FORCEPROP 2 LAST CDS_LIB pure_quanta_power
J 0
(-5325 1125);
DISPLAY INVISIBLE (-5325 1125);
FORCEPROP 1 LAST PATH I116
J 0
(-5250 1125);
DISPLAY 0.872340 (-5250 1125);
PAINT AQUA (-5250 1125);
DISPLAY INVISIBLE (-5250 1125);
FORCEPROP 1 LAST HDL_POWER GND
J 1
(-5300 1050);
DISPLAY 0.872340 (-5300 1050);
PAINT GREEN (-5300 1050);
DISPLAY INVISIBLE (-5300 1050);
FORCEADD Q_CAP..1
(-6475 650);
FORCEPROP 1 LAST LOCATION PC243
J 0
(-6425 750);
DISPLAY 0.489362 (-6425 750);
PAINT SKYBLUE (-6425 750);
FORCEPROP 0 LAST $SEC 1
J 0
(-6425 775);
DISPLAY 0.680851 (-6425 775);
PAINT MONO (-6425 775);
DISPLAY INVISIBLE (-6425 775);
FORCEPROP 0 LAST CDS_SEC 1
J 0
(-6425 775);
DISPLAY 1.021277 (-6425 775);
DISPLAY INVISIBLE (-6425 775);
FORCEPROP 1 LASTPIN (-6475 750) $PN 1
J 0
(-6465 730);
DISPLAY 0.489362 (-6465 730);
PAINT MONO (-6465 730);
FORCEPROP 1 LASTPIN (-6475 550) $PN 2
J 0
(-6465 530);
DISPLAY 0.489362 (-6465 530);
PAINT MONO (-6465 530);
FORCEPROP 1 LAST PACK_TYPE 0402
J 0
(-6425 450);
DISPLAY 0.489362 (-6425 450);
PAINT SKYBLUE (-6425 450);
FORCEPROP 1 LAST PART_NUMBER CH4104K1B00
J 0
(-6425 500);
DISPLAY 0.489362 (-6425 500);
PAINT SKYBLUE (-6425 500);
FORCEPROP 1 LAST VALUE 0.1UF
J 0
(-6425 700);
DISPLAY 0.489362 (-6425 700);
PAINT SKYBLUE (-6425 700);
FORCEPROP 1 LAST MATERIAL X7R
J 0
(-6425 550);
DISPLAY 0.489362 (-6425 550);
PAINT SKYBLUE (-6425 550);
FORCEPROP 1 LAST TOLERANCE 10%
J 0
(-6425 600);
DISPLAY 0.489362 (-6425 600);
PAINT SKYBLUE (-6425 600);
FORCEPROP 1 LAST VOLTAGE 25V
J 0
(-6425 650);
DISPLAY 0.489362 (-6425 650);
PAINT SKYBLUE (-6425 650);
FORCEPROP 2 LAST CDS_LIB pure_quanta
J 0
(-6475 650);
DISPLAY INVISIBLE (-6475 650);
FORCEPROP 1 LAST PATH I118
J 0
(-6425 800);
DISPLAY 0.978723 (-6425 800);
PAINT WHITE (-6425 800);
DISPLAY INVISIBLE (-6425 800);
FORCEADD OFFPAGE..4
R 2
(-9175 1425);
FORCEPROP 2 LAST $XR0 79 
J 0
(-9456 1425);
DISPLAY 0.638298 (-9456 1425);
PAINT MONO (-9456 1425);
FORCEPROP 2 LAST CDS_LIB standard
J 0
(-9175 1425);
DISPLAY INVISIBLE (-9175 1425);
FORCEPROP 1 LAST OFFPAGE TRUE
J 2
(-9500 1300);
DISPLAY 0.872340 (-9500 1300);
PAINT GREEN (-9500 1300);
DISPLAY INVISIBLE (-9500 1300);
FORCEPROP 1 LAST COMMENT_BODY TRUE
J 2
(-9150 1325);
DISPLAY 0.872340 (-9150 1325);
PAINT GREEN (-9150 1325);
DISPLAY INVISIBLE (-9150 1325);
FORCEPROP 2 LAST PATH I119
J 0
(-9125 1500);
DISPLAY 1.021277 (-9125 1500);
DISPLAY INVISIBLE (-9125 1500);
FORCEADD UNIVERSAL_GND..1
(-2925 5425);
FORCEPROP 3 LASTPIN (-2925 5475) SIG_NAME GND\g
J 0
(-2915 5485);
DISPLAY 0.659574 (-2915 5485);
PAINT MONO (-2915 5485);
DISPLAY INVISIBLE (-2915 5485);
FORCEPROP 2 LAST CDS_LIB pure_quanta_power
J 0
(-2925 5425);
DISPLAY INVISIBLE (-2925 5425);
FORCEPROP 1 LAST PATH I12
J 0
(-2850 5425);
DISPLAY 0.872340 (-2850 5425);
PAINT AQUA (-2850 5425);
DISPLAY INVISIBLE (-2850 5425);
FORCEPROP 1 LAST HDL_POWER GND
J 1
(-2900 5350);
DISPLAY 0.872340 (-2900 5350);
PAINT GREEN (-2900 5350);
DISPLAY INVISIBLE (-2900 5350);
FORCEADD Q_CAP..1
(-2925 5650);
FORCEPROP 1 LAST LOCATION PC251
J 0
(-2875 5750);
DISPLAY 0.489362 (-2875 5750);
PAINT SKYBLUE (-2875 5750);
FORCEPROP 0 LAST $SEC 1
J 0
(-2875 5775);
DISPLAY 0.680851 (-2875 5775);
PAINT MONO (-2875 5775);
DISPLAY INVISIBLE (-2875 5775);
FORCEPROP 0 LAST CDS_SEC 1
J 0
(-2875 5775);
DISPLAY 1.021277 (-2875 5775);
DISPLAY INVISIBLE (-2875 5775);
FORCEPROP 1 LASTPIN (-2925 5750) $PN 1
J 0
(-2915 5730);
DISPLAY 0.489362 (-2915 5730);
PAINT MONO (-2915 5730);
FORCEPROP 1 LASTPIN (-2925 5550) $PN 2
J 0
(-2915 5530);
DISPLAY 0.489362 (-2915 5530);
PAINT MONO (-2915 5530);
FORCEPROP 1 LAST MATERIAL X6S
J 0
(-2875 5550);
DISPLAY 0.489362 (-2875 5550);
PAINT SKYBLUE (-2875 5550);
FORCEPROP 1 LAST TOLERANCE 20%
J 0
(-2875 5600);
DISPLAY 0.489362 (-2875 5600);
PAINT SKYBLUE (-2875 5600);
FORCEPROP 1 LAST VALUE 10UF
J 0
(-2875 5700);
DISPLAY 0.489362 (-2875 5700);
PAINT SKYBLUE (-2875 5700);
FORCEPROP 1 LAST PART_NUMBER CH6101MEB01
J 0
(-2875 5500);
DISPLAY 0.489362 (-2875 5500);
PAINT SKYBLUE (-2875 5500);
FORCEPROP 1 LAST VOLTAGE 6.3V
J 0
(-2875 5650);
DISPLAY 0.489362 (-2875 5650);
PAINT SKYBLUE (-2875 5650);
FORCEPROP 1 LAST PACK_TYPE C0402
J 0
(-2875 5450);
DISPLAY 0.489362 (-2875 5450);
PAINT SKYBLUE (-2875 5450);
FORCEPROP 2 LAST CDS_LIB pure_quanta
J 0
(-2925 5650);
DISPLAY INVISIBLE (-2925 5650);
FORCEPROP 1 LAST PATH I13
J 0
(-2875 5800);
DISPLAY 0.978723 (-2875 5800);
PAINT WHITE (-2875 5800);
DISPLAY INVISIBLE (-2875 5800);
FORCEADD Q_RES..1
(-8600 1425);
FORCEPROP 1 LAST LOCATION PR149
J 0
(-8650 1475);
DISPLAY 0.489362 (-8650 1475);
PAINT SKYBLUE (-8650 1475);
FORCEPROP 0 LAST $SEC 1
J 0
(-8650 1500);
DISPLAY 0.680851 (-8650 1500);
PAINT MONO (-8650 1500);
DISPLAY INVISIBLE (-8650 1500);
FORCEPROP 0 LAST CDS_SEC 1
J 0
(-8650 1500);
DISPLAY 1.021277 (-8650 1500);
DISPLAY INVISIBLE (-8650 1500);
FORCEPROP 1 LASTPIN (-8700 1425) $PN 1
J 0
(-8688 1437);
DISPLAY 0.489362 (-8688 1437);
PAINT MONO (-8688 1437);
FORCEPROP 1 LASTPIN (-8500 1425) $PN 2
J 0
(-8538 1437);
DISPLAY 0.489362 (-8538 1437);
PAINT MONO (-8538 1437);
FORCEPROP 1 LAST WATTAGE 1/16W
J 0
(-8500 1375);
DISPLAY 0.489362 (-8500 1375);
PAINT SKYBLUE (-8500 1375);
FORCEPROP 1 LAST MATERIAL CHIP
J 0
(-8850 1350);
DISPLAY 0.489362 (-8850 1350);
PAINT SKYBLUE (-8850 1350);
FORCEPROP 1 LAST TOLERANCE 5%
J 0
(-8475 1475);
DISPLAY 0.489362 (-8475 1475);
PAINT SKYBLUE (-8475 1475);
FORCEPROP 1 LAST VALUE 0
J 2
(-8725 1475);
DISPLAY 0.489362 (-8725 1475);
PAINT SKYBLUE (-8725 1475);
FORCEPROP 1 LAST PART_NUMBER CS00002JB38
J 0
(-8850 1375);
DISPLAY 0.489362 (-8850 1375);
PAINT SKYBLUE (-8850 1375);
FORCEPROP 1 LAST PACK_TYPE 0402LF
J 0
(-8500 1350);
DISPLAY 0.489362 (-8500 1350);
PAINT SKYBLUE (-8500 1350);
FORCEPROP 2 LAST CDS_LIB pure_quanta
J 0
(-8600 1425);
DISPLAY INVISIBLE (-8600 1425);
FORCEPROP 1 LAST PATH I139
J 0
(-8650 1575);
DISPLAY 0.978723 (-8650 1575);
PAINT WHITE (-8650 1575);
DISPLAY INVISIBLE (-8650 1575);
FORCEADD VCC_CORE..1
(-2050 6375);
FORCEPROP 3 LASTPIN (-2050 6325) SIG_NAME P3V3_STBY\g
J 0
(-2040 6335);
DISPLAY 0.659574 (-2040 6335);
PAINT MONO (-2040 6335);
DISPLAY INVISIBLE (-2040 6335);
FORCEPROP 1 LAST HDL_POWER P3V3_STBY
J 1
(-2050 6425);
DISPLAY 0.489362 (-2050 6425);
PAINT GREEN (-2050 6425);
FORCEPROP 2 LAST CDS_LIB pure_quanta_power
J 0
(-2050 6375);
DISPLAY INVISIBLE (-2050 6375);
FORCEPROP 1 LAST PATH I14
J 0
(-2000 6400);
DISPLAY 0.872340 (-2000 6400);
PAINT AQUA (-2000 6400);
DISPLAY INVISIBLE (-2000 6400);
FORCEADD Q_CAP..1
(-8175 1225);
FORCEPROP 1 LAST LOCATION PC242
J 0
(-8125 1325);
DISPLAY 0.489362 (-8125 1325);
PAINT SKYBLUE (-8125 1325);
FORCEPROP 0 LAST $SEC 1
J 0
(-8125 1350);
DISPLAY 0.680851 (-8125 1350);
PAINT MONO (-8125 1350);
DISPLAY INVISIBLE (-8125 1350);
FORCEPROP 0 LAST CDS_SEC 1
J 0
(-8125 1350);
DISPLAY 1.021277 (-8125 1350);
DISPLAY INVISIBLE (-8125 1350);
FORCEPROP 1 LASTPIN (-8175 1325) $PN 1
J 0
(-8165 1305);
DISPLAY 0.489362 (-8165 1305);
PAINT MONO (-8165 1305);
FORCEPROP 1 LASTPIN (-8175 1125) $PN 2
J 0
(-8165 1105);
DISPLAY 0.489362 (-8165 1105);
PAINT MONO (-8165 1105);
FORCEPROP 1 LAST MATERIAL X7R
J 0
(-8125 1125);
DISPLAY 0.489362 (-8125 1125);
PAINT SKYBLUE (-8125 1125);
FORCEPROP 1 LAST TOLERANCE 5%
J 0
(-8125 1175);
DISPLAY 0.489362 (-8125 1175);
PAINT SKYBLUE (-8125 1175);
FORCEPROP 1 LAST VALUE 1000PF
J 0
(-8125 1275);
DISPLAY 0.489362 (-8125 1275);
PAINT SKYBLUE (-8125 1275);
FORCEPROP 1 LAST PART_NUMBER TMP_QCH21006JB10
J 0
(-8125 1075);
DISPLAY 0.489362 (-8125 1075);
PAINT SKYBLUE (-8125 1075);
FORCEPROP 1 LAST VOLTAGE 50V
J 0
(-8125 1225);
DISPLAY 0.489362 (-8125 1225);
PAINT SKYBLUE (-8125 1225);
FORCEPROP 1 LAST PACK_TYPE 0402
J 0
(-8125 1025);
DISPLAY 0.489362 (-8125 1025);
PAINT SKYBLUE (-8125 1025);
FORCEPROP 2 LAST CDS_LIB pure_quanta
J 0
(-8175 1225);
DISPLAY INVISIBLE (-8175 1225);
FORCEPROP 1 LAST PATH I140
J 0
(-8125 1375);
DISPLAY 0.978723 (-8125 1375);
PAINT WHITE (-8125 1375);
DISPLAY INVISIBLE (-8125 1375);
FORCEADD UNIVERSAL_GND..1
(-8175 1000);
FORCEPROP 3 LASTPIN (-8175 1050) SIG_NAME GND\g
J 0
(-8165 1060);
DISPLAY 0.659574 (-8165 1060);
PAINT MONO (-8165 1060);
DISPLAY INVISIBLE (-8165 1060);
FORCEPROP 2 LAST CDS_LIB pure_quanta_power
J 0
(-8175 1000);
DISPLAY INVISIBLE (-8175 1000);
FORCEPROP 1 LAST PATH I141
J 0
(-8100 1000);
DISPLAY 0.872340 (-8100 1000);
PAINT AQUA (-8100 1000);
DISPLAY INVISIBLE (-8100 1000);
FORCEPROP 1 LAST HDL_POWER GND
J 1
(-8150 925);
DISPLAY 0.872340 (-8150 925);
PAINT GREEN (-8150 925);
DISPLAY INVISIBLE (-8150 925);
FORCEADD UNIVERSAL_GND..1
(-7825 4775);
FORCEPROP 3 LASTPIN (-7825 4825) SIG_NAME GND\g
J 0
(-7815 4835);
DISPLAY 0.659574 (-7815 4835);
PAINT MONO (-7815 4835);
DISPLAY INVISIBLE (-7815 4835);
FORCEPROP 2 LAST CDS_LIB pure_quanta_power
J 0
(-7825 4775);
DISPLAY INVISIBLE (-7825 4775);
FORCEPROP 1 LAST PATH I144
J 0
(-7750 4775);
DISPLAY 0.872340 (-7750 4775);
PAINT AQUA (-7750 4775);
DISPLAY INVISIBLE (-7750 4775);
FORCEPROP 1 LAST HDL_POWER GND
J 1
(-7800 4700);
DISPLAY 0.872340 (-7800 4700);
PAINT GREEN (-7800 4700);
DISPLAY INVISIBLE (-7800 4700);
FORCEADD UNIVERSAL_GND..1
(-7550 4775);
FORCEPROP 3 LASTPIN (-7550 4825) SIG_NAME GND\g
J 0
(-7540 4835);
DISPLAY 0.659574 (-7540 4835);
PAINT MONO (-7540 4835);
DISPLAY INVISIBLE (-7540 4835);
FORCEPROP 2 LAST CDS_LIB pure_quanta_power
J 0
(-7550 4775);
DISPLAY INVISIBLE (-7550 4775);
FORCEPROP 1 LAST PATH I145
J 0
(-7475 4775);
DISPLAY 0.872340 (-7475 4775);
PAINT AQUA (-7475 4775);
DISPLAY INVISIBLE (-7475 4775);
FORCEPROP 1 LAST HDL_POWER GND
J 1
(-7525 4700);
DISPLAY 0.872340 (-7525 4700);
PAINT GREEN (-7525 4700);
DISPLAY INVISIBLE (-7525 4700);
FORCEADD Q_RES..1
(-6025 5350);
FORCEPROP 1 LAST LOCATION PR171
J 0
(-6075 5400);
DISPLAY 0.489362 (-6075 5400);
PAINT SKYBLUE (-6075 5400);
FORCEPROP 0 LAST $SEC 1
J 0
(-6075 5425);
DISPLAY 0.680851 (-6075 5425);
PAINT MONO (-6075 5425);
DISPLAY INVISIBLE (-6075 5425);
FORCEPROP 0 LAST CDS_SEC 1
J 0
(-6075 5425);
DISPLAY 1.021277 (-6075 5425);
DISPLAY INVISIBLE (-6075 5425);
FORCEPROP 1 LASTPIN (-6125 5350) $PN 1
J 0
(-6113 5362);
DISPLAY 0.489362 (-6113 5362);
PAINT MONO (-6113 5362);
FORCEPROP 1 LASTPIN (-5925 5350) $PN 2
J 0
(-5963 5362);
DISPLAY 0.489362 (-5963 5362);
PAINT MONO (-5963 5362);
FORCEPROP 1 LAST WATTAGE 1/16W
J 0
(-5925 5300);
DISPLAY 0.489362 (-5925 5300);
PAINT SKYBLUE (-5925 5300);
FORCEPROP 1 LAST MATERIAL CHIP
J 0
(-6275 5275);
DISPLAY 0.489362 (-6275 5275);
PAINT SKYBLUE (-6275 5275);
FORCEPROP 1 LAST TOLERANCE 5%
J 0
(-5900 5375);
DISPLAY 0.489362 (-5900 5375);
PAINT SKYBLUE (-5900 5375);
FORCEPROP 1 LAST VALUE 0
J 2
(-6150 5375);
DISPLAY 0.489362 (-6150 5375);
PAINT SKYBLUE (-6150 5375);
FORCEPROP 1 LAST PART_NUMBER CS00002JB38
J 0
(-6275 5300);
DISPLAY 0.489362 (-6275 5300);
PAINT SKYBLUE (-6275 5300);
FORCEPROP 1 LAST PACK_TYPE 0402LF
J 0
(-5925 5275);
DISPLAY 0.489362 (-5925 5275);
PAINT SKYBLUE (-5925 5275);
FORCEPROP 2 LAST CDS_LIB pure_quanta
J 0
(-6025 5350);
DISPLAY INVISIBLE (-6025 5350);
FORCEPROP 1 LAST PATH I148
J 0
(-6075 5500);
DISPLAY 0.978723 (-6075 5500);
PAINT WHITE (-6075 5500);
DISPLAY INVISIBLE (-6075 5500);
FORCEADD Q_RES..1
(-6025 5200);
FORCEPROP 1 LAST LOCATION PR172
J 0
(-6075 5250);
DISPLAY 0.489362 (-6075 5250);
PAINT SKYBLUE (-6075 5250);
FORCEPROP 0 LAST $SEC 1
J 0
(-6075 5275);
DISPLAY 0.680851 (-6075 5275);
PAINT MONO (-6075 5275);
DISPLAY INVISIBLE (-6075 5275);
FORCEPROP 0 LAST CDS_SEC 1
J 0
(-6075 5275);
DISPLAY 1.021277 (-6075 5275);
DISPLAY INVISIBLE (-6075 5275);
FORCEPROP 1 LASTPIN (-6125 5200) $PN 1
J 0
(-6113 5212);
DISPLAY 0.489362 (-6113 5212);
PAINT MONO (-6113 5212);
FORCEPROP 1 LASTPIN (-5925 5200) $PN 2
J 0
(-5963 5212);
DISPLAY 0.489362 (-5963 5212);
PAINT MONO (-5963 5212);
FORCEPROP 1 LAST WATTAGE 1/16W
J 0
(-5925 5150);
DISPLAY 0.489362 (-5925 5150);
PAINT SKYBLUE (-5925 5150);
FORCEPROP 1 LAST MATERIAL CHIP
J 0
(-6275 5125);
DISPLAY 0.489362 (-6275 5125);
PAINT SKYBLUE (-6275 5125);
FORCEPROP 1 LAST TOLERANCE 5%
J 0
(-5900 5225);
DISPLAY 0.489362 (-5900 5225);
PAINT SKYBLUE (-5900 5225);
FORCEPROP 1 LAST VALUE 0
J 2
(-6150 5225);
DISPLAY 0.489362 (-6150 5225);
PAINT SKYBLUE (-6150 5225);
FORCEPROP 1 LAST PART_NUMBER CS00002JB38
J 0
(-6275 5150);
DISPLAY 0.489362 (-6275 5150);
PAINT SKYBLUE (-6275 5150);
FORCEPROP 1 LAST PACK_TYPE 0402LF
J 0
(-5925 5125);
DISPLAY 0.489362 (-5925 5125);
PAINT SKYBLUE (-5925 5125);
FORCEPROP 2 LAST CDS_LIB pure_quanta
J 0
(-6025 5200);
DISPLAY INVISIBLE (-6025 5200);
FORCEPROP 1 LAST PATH I149
J 0
(-6075 5350);
DISPLAY 0.978723 (-6075 5350);
PAINT WHITE (-6075 5350);
DISPLAY INVISIBLE (-6075 5350);
FORCEADD OFFPAGE..5
R 2
(-2475 5800);
FORCEPROP 2 LAST $XR4 192 
J 0
(-1806 5800);
DISPLAY 0.638298 (-1806 5800);
PAINT MONO (-1806 5800);
FORCEPROP 2 LAST $XR3 191 
J 0
(-1926 5800);
DISPLAY 0.638298 (-1926 5800);
PAINT MONO (-1926 5800);
FORCEPROP 2 LAST $XR2 189 
J 0
(-2046 5800);
DISPLAY 0.638298 (-2046 5800);
PAINT MONO (-2046 5800);
FORCEPROP 2 LAST $XR1 188 
J 0
(-2166 5800);
DISPLAY 0.638298 (-2166 5800);
PAINT MONO (-2166 5800);
FORCEPROP 2 LAST $XR0 187 
J 0
(-2286 5800);
DISPLAY 0.638298 (-2286 5800);
PAINT MONO (-2286 5800);
FORCEPROP 2 LAST CDS_LIB standard
J 2
(-2475 5800);
DISPLAY INVISIBLE (-2475 5800);
FORCEPROP 1 LAST OFFPAGE TRUE
J 2
(-2800 5675);
DISPLAY 0.872340 (-2800 5675);
PAINT GREEN (-2800 5675);
DISPLAY INVISIBLE (-2800 5675);
FORCEPROP 1 LAST COMMENT_BODY TRUE
J 2
(-2575 5725);
DISPLAY 0.872340 (-2575 5725);
PAINT GREEN (-2575 5725);
DISPLAY INVISIBLE (-2575 5725);
FORCEPROP 2 LAST PATH I15
J 2
(-2525 5875);
DISPLAY 1.021277 (-2525 5875);
DISPLAY INVISIBLE (-2525 5875);
FORCEADD OFFPAGE..4
R 2
(-6625 5950);
FORCEPROP 2 LAST $XR0 80 
J 0
(-6846 5950);
DISPLAY 0.638298 (-6846 5950);
PAINT MONO (-6846 5950);
FORCEPROP 2 LAST CDS_LIB standard
J 0
(-6625 5950);
DISPLAY INVISIBLE (-6625 5950);
FORCEPROP 1 LAST OFFPAGE TRUE
J 2
(-6950 5825);
DISPLAY 0.872340 (-6950 5825);
PAINT GREEN (-6950 5825);
DISPLAY INVISIBLE (-6950 5825);
FORCEPROP 1 LAST COMMENT_BODY TRUE
J 2
(-6600 5850);
DISPLAY 0.872340 (-6600 5850);
PAINT GREEN (-6600 5850);
DISPLAY INVISIBLE (-6600 5850);
FORCEPROP 2 LAST PATH I150
J 0
(-6575 6025);
DISPLAY 1.021277 (-6575 6025);
DISPLAY INVISIBLE (-6575 6025);
FORCEADD Q_RES..1
(-2475 6275);
FORCEPROP 1 LAST LOCATION PR183
J 0
(-2525 6325);
DISPLAY 0.489362 (-2525 6325);
PAINT SKYBLUE (-2525 6325);
FORCEPROP 0 LAST $SEC 1
J 0
(-2525 6375);
DISPLAY 0.680851 (-2525 6375);
PAINT MONO (-2525 6375);
DISPLAY INVISIBLE (-2525 6375);
FORCEPROP 0 LAST CDS_SEC 1
J 0
(-2525 6375);
DISPLAY 1.021277 (-2525 6375);
DISPLAY INVISIBLE (-2525 6375);
FORCEPROP 1 LASTPIN (-2575 6275) $PN 1
J 0
(-2563 6287);
DISPLAY 0.489362 (-2563 6287);
PAINT MONO (-2563 6287);
FORCEPROP 1 LASTPIN (-2375 6275) $PN 2
J 0
(-2413 6287);
DISPLAY 0.489362 (-2413 6287);
PAINT MONO (-2413 6287);
FORCEPROP 1 LAST WATTAGE 1/16W
J 0
(-2350 6200);
DISPLAY 0.489362 (-2350 6200);
PAINT SKYBLUE (-2350 6200);
FORCEPROP 1 LAST MATERIAL CHIP
J 0
(-2350 6225);
DISPLAY 0.489362 (-2350 6225);
PAINT SKYBLUE (-2350 6225);
FORCEPROP 1 LAST TOLERANCE 1%
J 0
(-2350 6300);
DISPLAY 0.489362 (-2350 6300);
PAINT SKYBLUE (-2350 6300);
FORCEPROP 1 LAST VALUE 1
J 2
(-2625 6300);
DISPLAY 0.489362 (-2625 6300);
PAINT SKYBLUE (-2625 6300);
FORCEPROP 1 LAST PART_NUMBER CS-1002FB23
J 0
(-2650 6225);
DISPLAY 0.489362 (-2650 6225);
PAINT SKYBLUE (-2650 6225);
FORCEPROP 1 LAST PACK_TYPE 0402LF
J 0
(-2650 6200);
DISPLAY 0.489362 (-2650 6200);
PAINT SKYBLUE (-2650 6200);
FORCEPROP 2 LAST CDS_LIB pure_quanta
J 0
(-2475 6275);
DISPLAY INVISIBLE (-2475 6275);
FORCEPROP 1 LAST PATH I151
J 0
(-2525 6425);
DISPLAY 0.978723 (-2525 6425);
PAINT WHITE (-2525 6425);
DISPLAY INVISIBLE (-2525 6425);
FORCEADD OFFPAGE..4
(-2475 1200);
FORCEPROP 2 LAST $XR1 192 
J 0
(-2169 1200);
DISPLAY 0.638298 (-2169 1200);
PAINT MONO (-2169 1200);
FORCEPROP 2 LAST $XR0 191 
J 0
(-2289 1200);
DISPLAY 0.638298 (-2289 1200);
PAINT MONO (-2289 1200);
FORCEPROP 2 LAST CDS_LIB standard
J 0
(-2475 1200);
DISPLAY INVISIBLE (-2475 1200);
FORCEPROP 1 LAST OFFPAGE TRUE
J 0
(-2150 1075);
DISPLAY 0.872340 (-2150 1075);
PAINT GREEN (-2150 1075);
DISPLAY INVISIBLE (-2150 1075);
FORCEPROP 1 LAST COMMENT_BODY TRUE
J 0
(-2500 1100);
DISPLAY 0.872340 (-2500 1100);
PAINT GREEN (-2500 1100);
DISPLAY INVISIBLE (-2500 1100);
FORCEPROP 2 LAST PATH I152
J 0
(-2300 1275);
DISPLAY 1.021277 (-2300 1275);
DISPLAY INVISIBLE (-2300 1275);
FORCEADD OFFPAGE..4
(-3050 900);
FORCEPROP 2 LAST $XR2 189 
J 0
(-2864 936);
DISPLAY 0.638298 (-2864 936);
PAINT MONO (-2864 936);
FORCEPROP 2 LAST $XR1 188 
J 0
(-2864 864);
DISPLAY 0.638298 (-2864 864);
PAINT MONO (-2864 864);
FORCEPROP 2 LAST $XR0 187 
J 0
(-2864 900);
DISPLAY 0.638298 (-2864 900);
PAINT MONO (-2864 900);
FORCEPROP 2 LAST CDS_LIB standard
J 0
(-3050 900);
DISPLAY INVISIBLE (-3050 900);
FORCEPROP 1 LAST OFFPAGE TRUE
J 0
(-2725 775);
DISPLAY 0.872340 (-2725 775);
PAINT GREEN (-2725 775);
DISPLAY INVISIBLE (-2725 775);
FORCEPROP 1 LAST COMMENT_BODY TRUE
J 0
(-3075 800);
DISPLAY 0.872340 (-3075 800);
PAINT GREEN (-3075 800);
DISPLAY INVISIBLE (-3075 800);
FORCEPROP 2 LAST PATH I153
J 0
(-2875 975);
DISPLAY 1.021277 (-2875 975);
DISPLAY INVISIBLE (-2875 975);
FORCEADD MOSFET_PCH_GDS_ESD_PROTECTED..1
R 6
(-7125 1850);
FORCEPROP 1 LAST LOCATION PQ11
J 0
(-6950 1700);
DISPLAY 0.489362 (-6950 1700);
PAINT SKYBLUE (-6950 1700);
FORCEPROP 0 LAST $SEC 1
J 0
(-6950 1875);
DISPLAY 0.680851 (-6950 1875);
PAINT MONO (-6950 1875);
DISPLAY INVISIBLE (-6950 1875);
FORCEPROP 0 LAST CDS_SEC 1
J 0
(-6950 1875);
DISPLAY 1.021277 (-6950 1875);
DISPLAY INVISIBLE (-6950 1875);
FORCEPROP 0 LASTPIN (-7100 1550) $PN D
R 1
J 2
(-7110 1540);
DISPLAY 0.489362 (-7110 1540);
PAINT MONO (-7110 1540);
FORCEPROP 0 LASTPIN (-7400 1850) $PN G
J 2
(-7410 1860);
DISPLAY 0.489362 (-7410 1860);
PAINT MONO (-7410 1860);
FORCEPROP 0 LASTPIN (-7100 2150) $PN S
R 1
J 0
(-7110 2160);
DISPLAY 0.489362 (-7110 2160);
PAINT MONO (-7110 2160);
FORCEPROP 1 LAST MATERIAL IC
J 0
(-6950 1852);
DISPLAY 0.489362 (-6950 1852);
PAINT SKYBLUE (-6950 1852);
FORCEPROP 2 LAST VALUE PJA3415AE
J 0
(-6950 1802);
DISPLAY 0.489362 (-6950 1802);
PAINT SKYBLUE (-6950 1802);
FORCEPROP 1 LAST PART_NUMBER BAM34150008
J 0
(-6950 1752);
DISPLAY 0.489362 (-6950 1752);
PAINT SKYBLUE (-6950 1752);
FORCEPROP 2 LAST CDS_LIB pure_quanta
J 0
(-7125 1850);
DISPLAY INVISIBLE (-7125 1850);
FORCEPROP 1 LAST CDS_LMAN_SYM_OUTLINE -125,150,125,-150
J 0
(-7125 1850);
DISPLAY 0.468085 (-7125 1850);
PAINT GREEN (-7125 1850);
DISPLAY INVISIBLE (-7125 1850);
FORCEPROP 1 LAST NEEDS_NO_SIZE TRUE
J 0
(-7125 1816);
DISPLAY 0.723404 (-7125 1816);
PAINT GREEN (-7125 1816);
DISPLAY INVISIBLE (-7125 1816);
FORCEPROP 2 LAST PART_TYPE SMLF
J 0
(-6975 1677);
DISPLAY 1.021277 (-6975 1677);
DISPLAY INVISIBLE (-6975 1677);
FORCEPROP 1 LAST PATH I154
J 0
(-7125 1850);
DISPLAY 0.723404 (-7125 1850);
PAINT GREEN (-7125 1850);
DISPLAY INVISIBLE (-7125 1850);
FORCEADD UNIVERSAL_GND..1
(-3250 5425);
FORCEPROP 3 LASTPIN (-3250 5475) SIG_NAME GND\g
J 0
(-3240 5485);
DISPLAY 0.659574 (-3240 5485);
PAINT MONO (-3240 5485);
DISPLAY INVISIBLE (-3240 5485);
FORCEPROP 2 LAST CDS_LIB pure_quanta_power
J 0
(-3250 5425);
DISPLAY INVISIBLE (-3250 5425);
FORCEPROP 1 LAST PATH I155
J 0
(-3175 5425);
DISPLAY 0.872340 (-3175 5425);
PAINT AQUA (-3175 5425);
DISPLAY INVISIBLE (-3175 5425);
FORCEPROP 1 LAST HDL_POWER GND
J 1
(-3225 5350);
DISPLAY 0.872340 (-3225 5350);
PAINT GREEN (-3225 5350);
DISPLAY INVISIBLE (-3225 5350);
FORCEADD Q_CAP..1
(-3250 5650);
FORCEPROP 1 LAST LOCATION PC11
J 0
(-3200 5750);
DISPLAY 0.489362 (-3200 5750);
PAINT SKYBLUE (-3200 5750);
FORCEPROP 0 LAST $SEC 1
J 0
(-3200 5775);
DISPLAY 0.680851 (-3200 5775);
PAINT MONO (-3200 5775);
DISPLAY INVISIBLE (-3200 5775);
FORCEPROP 0 LAST CDS_SEC 1
J 0
(-3200 5775);
DISPLAY 1.021277 (-3200 5775);
DISPLAY INVISIBLE (-3200 5775);
FORCEPROP 1 LASTPIN (-3250 5750) $PN 1
J 0
(-3240 5730);
DISPLAY 0.489362 (-3240 5730);
PAINT MONO (-3240 5730);
FORCEPROP 1 LASTPIN (-3250 5550) $PN 2
J 0
(-3240 5530);
DISPLAY 0.489362 (-3240 5530);
PAINT MONO (-3240 5530);
FORCEPROP 1 LAST MATERIAL X7R
J 0
(-3200 5550);
DISPLAY 0.489362 (-3200 5550);
PAINT SKYBLUE (-3200 5550);
FORCEPROP 1 LAST TOLERANCE 10%
J 0
(-3200 5600);
DISPLAY 0.489362 (-3200 5600);
PAINT SKYBLUE (-3200 5600);
FORCEPROP 1 LAST VALUE 0.1UF
J 0
(-3200 5700);
DISPLAY 0.489362 (-3200 5700);
PAINT SKYBLUE (-3200 5700);
FORCEPROP 1 LAST PART_NUMBER CH4104K1B00
J 0
(-3200 5500);
DISPLAY 0.489362 (-3200 5500);
PAINT SKYBLUE (-3200 5500);
FORCEPROP 1 LAST VOLTAGE 25V
J 0
(-3200 5650);
DISPLAY 0.489362 (-3200 5650);
PAINT SKYBLUE (-3200 5650);
FORCEPROP 1 LAST PACK_TYPE 0402
J 0
(-3200 5450);
DISPLAY 0.489362 (-3200 5450);
PAINT SKYBLUE (-3200 5450);
FORCEPROP 2 LAST CDS_LIB pure_quanta
J 0
(-3250 5650);
DISPLAY INVISIBLE (-3250 5650);
FORCEPROP 1 LAST PATH I156
J 0
(-3200 5800);
DISPLAY 0.978723 (-3200 5800);
PAINT WHITE (-3200 5800);
DISPLAY INVISIBLE (-3200 5800);
FORCEADD UNIVERSAL_GND..1
(-3250 5875);
FORCEPROP 3 LASTPIN (-3250 5925) SIG_NAME GND\g
J 0
(-3240 5935);
DISPLAY 0.659574 (-3240 5935);
PAINT MONO (-3240 5935);
DISPLAY INVISIBLE (-3240 5935);
FORCEPROP 2 LAST CDS_LIB pure_quanta_power
J 0
(-3250 5875);
DISPLAY INVISIBLE (-3250 5875);
FORCEPROP 1 LAST PATH I157
J 0
(-3175 5875);
DISPLAY 0.872340 (-3175 5875);
PAINT AQUA (-3175 5875);
DISPLAY INVISIBLE (-3175 5875);
FORCEPROP 1 LAST HDL_POWER GND
J 1
(-3225 5800);
DISPLAY 0.872340 (-3225 5800);
PAINT GREEN (-3225 5800);
DISPLAY INVISIBLE (-3225 5800);
FORCEADD Q_CAP..1
(-3250 6125);
FORCEPROP 1 LAST LOCATION PC10
J 0
(-3200 6225);
DISPLAY 0.489362 (-3200 6225);
PAINT SKYBLUE (-3200 6225);
FORCEPROP 0 LAST $SEC 1
J 0
(-3200 6250);
DISPLAY 0.680851 (-3200 6250);
PAINT MONO (-3200 6250);
DISPLAY INVISIBLE (-3200 6250);
FORCEPROP 0 LAST CDS_SEC 1
J 0
(-3200 6250);
DISPLAY 1.021277 (-3200 6250);
DISPLAY INVISIBLE (-3200 6250);
FORCEPROP 1 LASTPIN (-3250 6225) $PN 1
J 0
(-3240 6205);
DISPLAY 0.489362 (-3240 6205);
PAINT MONO (-3240 6205);
FORCEPROP 1 LASTPIN (-3250 6025) $PN 2
J 0
(-3240 6005);
DISPLAY 0.489362 (-3240 6005);
PAINT MONO (-3240 6005);
FORCEPROP 1 LAST MATERIAL X7R
J 0
(-3200 6025);
DISPLAY 0.489362 (-3200 6025);
PAINT SKYBLUE (-3200 6025);
FORCEPROP 1 LAST TOLERANCE 10%
J 0
(-3200 6075);
DISPLAY 0.489362 (-3200 6075);
PAINT SKYBLUE (-3200 6075);
FORCEPROP 1 LAST VALUE 0.1UF
J 0
(-3200 6175);
DISPLAY 0.489362 (-3200 6175);
PAINT SKYBLUE (-3200 6175);
FORCEPROP 1 LAST PART_NUMBER CH4104K1B00
J 0
(-3200 5975);
DISPLAY 0.489362 (-3200 5975);
PAINT SKYBLUE (-3200 5975);
FORCEPROP 1 LAST VOLTAGE 25V
J 0
(-3200 6125);
DISPLAY 0.489362 (-3200 6125);
PAINT SKYBLUE (-3200 6125);
FORCEPROP 1 LAST PACK_TYPE 0402
J 0
(-3200 5925);
DISPLAY 0.489362 (-3200 5925);
PAINT SKYBLUE (-3200 5925);
FORCEPROP 2 LAST CDS_LIB pure_quanta
J 0
(-3250 6125);
DISPLAY INVISIBLE (-3250 6125);
FORCEPROP 1 LAST PATH I158
J 0
(-3200 6275);
DISPLAY 0.978723 (-3200 6275);
PAINT WHITE (-3200 6275);
DISPLAY INVISIBLE (-3200 6275);
FORCEADD OFFPAGE..5
(-6725 2100);
FORCEPROP 2 LAST $XR0 81 
J 0
(-6979 2100);
DISPLAY 0.638298 (-6979 2100);
PAINT MONO (-6979 2100);
FORCEPROP 2 LAST CDS_LIB standard
J 0
(-6725 2100);
DISPLAY INVISIBLE (-6725 2100);
FORCEPROP 1 LAST OFFPAGE TRUE
J 0
(-6400 1975);
DISPLAY 0.872340 (-6400 1975);
PAINT GREEN (-6400 1975);
DISPLAY INVISIBLE (-6400 1975);
FORCEPROP 1 LAST COMMENT_BODY TRUE
J 0
(-6625 2025);
DISPLAY 0.872340 (-6625 2025);
PAINT GREEN (-6625 2025);
DISPLAY INVISIBLE (-6625 2025);
FORCEPROP 2 LAST PATH I173
J 0
(-6675 2175);
DISPLAY 1.021277 (-6675 2175);
DISPLAY INVISIBLE (-6675 2175);
FORCEADD VCC_CORE..1
(-6225 1800);
FORCEPROP 3 LASTPIN (-6225 1750) SIG_NAME PVDD18_S5_P1\g
J 0
(-6215 1760);
DISPLAY 0.659574 (-6215 1760);
PAINT MONO (-6215 1760);
DISPLAY INVISIBLE (-6215 1760);
FORCEPROP 1 LAST HDL_POWER PVDD18_S5_P1
J 1
(-6225 1850);
DISPLAY 0.489362 (-6225 1850);
PAINT GREEN (-6225 1850);
FORCEPROP 2 LAST CDS_LIB pure_quanta_power
J 0
(-6225 1800);
DISPLAY INVISIBLE (-6225 1800);
FORCEPROP 1 LAST PATH I174
J 0
(-6175 1825);
DISPLAY 0.872340 (-6175 1825);
PAINT AQUA (-6175 1825);
DISPLAY INVISIBLE (-6175 1825);
FORCEADD Q_CAP..2
(-5675 1725);
FORCEPROP 1 LAST LOCATION PC247
J 1
(-5675 1775);
DISPLAY 0.489362 (-5675 1775);
PAINT SKYBLUE (-5675 1775);
FORCEPROP 0 LAST $SEC 1
J 0
(-5100 1800);
DISPLAY 0.680851 (-5100 1800);
PAINT MONO (-5100 1800);
DISPLAY INVISIBLE (-5100 1800);
FORCEPROP 0 LAST CDS_SEC 1
J 0
(-5100 1800);
DISPLAY 1.021277 (-5100 1800);
DISPLAY INVISIBLE (-5100 1800);
FORCEPROP 1 LASTPIN (-5775 1725) $PN 1
J 0
(-5785 1740);
DISPLAY 0.489362 (-5785 1740);
PAINT MONO (-5785 1740);
FORCEPROP 1 LASTPIN (-5575 1725) $PN 2
J 0
(-5590 1740);
DISPLAY 0.489362 (-5590 1740);
PAINT MONO (-5590 1740);
FORCEPROP 1 LAST MATERIAL X7R
J 0
(-5875 1600);
DISPLAY 0.489362 (-5875 1600);
PAINT SKYBLUE (-5875 1600);
FORCEPROP 1 LAST TOLERANCE 10%
J 2
(-5450 1600);
DISPLAY 0.489362 (-5450 1600);
PAINT SKYBLUE (-5450 1600);
FORCEPROP 1 LAST VALUE 1UF
J 2
(-5825 1775);
DISPLAY 0.489362 (-5825 1775);
PAINT SKYBLUE (-5825 1775);
FORCEPROP 1 LAST PART_NUMBER CH5101K1B01
J 1
(-5800 1650);
DISPLAY 0.489362 (-5800 1650);
PAINT SKYBLUE (-5800 1650);
FORCEPROP 1 LAST VOLTAGE 6.3V
J 0
(-5525 1775);
DISPLAY 0.489362 (-5525 1775);
PAINT SKYBLUE (-5525 1775);
FORCEPROP 1 LAST PACK_TYPE 0402
J 1
(-5500 1650);
DISPLAY 0.489362 (-5500 1650);
PAINT SKYBLUE (-5500 1650);
FORCEPROP 2 LAST CDS_LIB pure_quanta
J 0
(-5675 1725);
DISPLAY INVISIBLE (-5675 1725);
FORCEPROP 1 LAST PATH I175
J 0
(-5675 1925);
DISPLAY 0.978723 (-5675 1925);
PAINT WHITE (-5675 1925);
DISPLAY INVISIBLE (-5675 1925);
FORCEADD OFFPAGE..1
(-6725 2250);
FORCEPROP 2 LAST $XR0 77 
J 0
(-6946 2250);
DISPLAY 0.638298 (-6946 2250);
PAINT MONO (-6946 2250);
FORCEPROP 2 LAST CDS_LIB standard
J 0
(-6725 2250);
DISPLAY INVISIBLE (-6725 2250);
FORCEPROP 1 LAST OFFPAGE TRUE
J 0
(-6400 2125);
DISPLAY 0.872340 (-6400 2125);
PAINT GREEN (-6400 2125);
DISPLAY INVISIBLE (-6400 2125);
FORCEPROP 1 LAST COMMENT_BODY TRUE
J 0
(-6600 2150);
DISPLAY 0.872340 (-6600 2150);
PAINT GREEN (-6600 2150);
DISPLAY INVISIBLE (-6600 2150);
FORCEPROP 2 LAST PATH I176
J 0
(-6675 2325);
DISPLAY 1.021277 (-6675 2325);
DISPLAY INVISIBLE (-6675 2325);
FORCEADD VCC_CORE..1
(-6525 2525);
FORCEPROP 3 LASTPIN (-6525 2475) SIG_NAME PVDD18_S5_P1\g
J 0
(-6515 2485);
DISPLAY 0.659574 (-6515 2485);
PAINT MONO (-6515 2485);
DISPLAY INVISIBLE (-6515 2485);
FORCEPROP 1 LAST HDL_POWER PVDD18_S5_P1
J 1
(-6525 2575);
DISPLAY 0.489362 (-6525 2575);
PAINT GREEN (-6525 2575);
FORCEPROP 2 LAST CDS_LIB pure_quanta_power
J 0
(-6525 2525);
DISPLAY INVISIBLE (-6525 2525);
FORCEPROP 1 LAST PATH I177
J 0
(-6475 2550);
DISPLAY 0.872340 (-6475 2550);
PAINT AQUA (-6475 2550);
DISPLAY INVISIBLE (-6475 2550);
FORCEADD Q_RES..1
(-6050 2100);
FORCEPROP 1 LAST LOCATION PR168
J 0
(-6100 2150);
DISPLAY 0.489362 (-6100 2150);
PAINT SKYBLUE (-6100 2150);
FORCEPROP 0 LAST $SEC 1
J 0
(-6100 2175);
DISPLAY 0.680851 (-6100 2175);
PAINT MONO (-6100 2175);
DISPLAY INVISIBLE (-6100 2175);
FORCEPROP 0 LAST CDS_SEC 1
J 0
(-6100 2175);
DISPLAY 1.021277 (-6100 2175);
DISPLAY INVISIBLE (-6100 2175);
FORCEPROP 1 LASTPIN (-6150 2100) $PN 1
J 0
(-6138 2112);
DISPLAY 0.489362 (-6138 2112);
PAINT MONO (-6138 2112);
FORCEPROP 1 LASTPIN (-5950 2100) $PN 2
J 0
(-5988 2112);
DISPLAY 0.489362 (-5988 2112);
PAINT MONO (-5988 2112);
FORCEPROP 1 LAST WATTAGE 1/16W
J 2
(-6125 2050);
DISPLAY 0.489362 (-6125 2050);
PAINT SKYBLUE (-6125 2050);
FORCEPROP 1 LAST MATERIAL CHIP
J 0
(-6375 2050);
DISPLAY 0.489362 (-6375 2050);
PAINT SKYBLUE (-6375 2050);
FORCEPROP 1 LAST TOLERANCE 5%
J 0
(-6025 2050);
DISPLAY 0.489362 (-6025 2050);
PAINT SKYBLUE (-6025 2050);
FORCEPROP 1 LAST VALUE 0
J 2
(-6050 2050);
DISPLAY 0.489362 (-6050 2050);
PAINT SKYBLUE (-6050 2050);
FORCEPROP 1 LAST PART_NUMBER CS00002JB38
J 0
(-6725 2050);
DISPLAY 0.489362 (-6725 2050);
PAINT SKYBLUE (-6725 2050);
FORCEPROP 1 LAST PACK_TYPE 0402LF
J 0
(-5950 2050);
DISPLAY 0.489362 (-5950 2050);
PAINT SKYBLUE (-5950 2050);
FORCEPROP 2 LAST CDS_LIB pure_quanta
J 0
(-6050 2100);
DISPLAY INVISIBLE (-6050 2100);
FORCEPROP 1 LAST PATH I178
J 0
(-6100 2250);
DISPLAY 0.978723 (-6100 2250);
PAINT WHITE (-6100 2250);
DISPLAY INVISIBLE (-6100 2250);
FORCEADD Q_RES..1
(-6050 2250);
FORCEPROP 1 LAST LOCATION PR182
J 0
(-6100 2300);
DISPLAY 0.489362 (-6100 2300);
PAINT SKYBLUE (-6100 2300);
FORCEPROP 0 LAST $SEC 1
J 0
(-6100 2325);
DISPLAY 0.680851 (-6100 2325);
PAINT MONO (-6100 2325);
DISPLAY INVISIBLE (-6100 2325);
FORCEPROP 0 LAST CDS_SEC 1
J 0
(-6100 2325);
DISPLAY 1.021277 (-6100 2325);
DISPLAY INVISIBLE (-6100 2325);
FORCEPROP 1 LASTPIN (-6150 2250) $PN 1
J 0
(-6138 2262);
DISPLAY 0.489362 (-6138 2262);
PAINT MONO (-6138 2262);
FORCEPROP 1 LASTPIN (-5950 2250) $PN 2
J 0
(-5988 2262);
DISPLAY 0.489362 (-5988 2262);
PAINT MONO (-5988 2262);
FORCEPROP 1 LAST WATTAGE 1/16W
J 2
(-6125 2200);
DISPLAY 0.489362 (-6125 2200);
PAINT SKYBLUE (-6125 2200);
FORCEPROP 1 LAST MATERIAL CHIP
J 0
(-6375 2200);
DISPLAY 0.489362 (-6375 2200);
PAINT SKYBLUE (-6375 2200);
FORCEPROP 1 LAST TOLERANCE 5%
J 0
(-6025 2200);
DISPLAY 0.489362 (-6025 2200);
PAINT SKYBLUE (-6025 2200);
FORCEPROP 1 LAST VALUE 0
J 2
(-6050 2200);
DISPLAY 0.489362 (-6050 2200);
PAINT SKYBLUE (-6050 2200);
FORCEPROP 1 LAST PART_NUMBER CS00002JB38
J 0
(-6725 2200);
DISPLAY 0.489362 (-6725 2200);
PAINT SKYBLUE (-6725 2200);
FORCEPROP 1 LAST PACK_TYPE 0402LF
J 0
(-5950 2200);
DISPLAY 0.489362 (-5950 2200);
PAINT SKYBLUE (-5950 2200);
FORCEPROP 2 LAST CDS_LIB pure_quanta
J 0
(-6050 2250);
DISPLAY INVISIBLE (-6050 2250);
FORCEPROP 1 LAST PATH I179
J 0
(-6100 2400);
DISPLAY 0.978723 (-6100 2400);
PAINT WHITE (-6100 2400);
DISPLAY INVISIBLE (-6100 2400);
FORCEADD Q_RES..1
(-6075 2400);
FORCEPROP 1 LAST LOCATION PR184
J 0
(-6450 2425);
DISPLAY 0.489362 (-6450 2425);
PAINT SKYBLUE (-6450 2425);
FORCEPROP 0 LAST $SEC 1
J 0
(-6325 2500);
DISPLAY 0.680851 (-6325 2500);
PAINT MONO (-6325 2500);
DISPLAY INVISIBLE (-6325 2500);
FORCEPROP 0 LAST CDS_SEC 1
J 0
(-6325 2500);
DISPLAY 1.021277 (-6325 2500);
DISPLAY INVISIBLE (-6325 2500);
FORCEPROP 1 LASTPIN (-6175 2400) $PN 1
J 0
(-6163 2412);
DISPLAY 0.489362 (-6163 2412);
PAINT MONO (-6163 2412);
FORCEPROP 1 LASTPIN (-5975 2400) $PN 2
J 0
(-6013 2412);
DISPLAY 0.489362 (-6013 2412);
PAINT MONO (-6013 2412);
FORCEPROP 1 LAST WATTAGE 1/16W
J 2
(-5800 2425);
DISPLAY 0.489362 (-5800 2425);
PAINT SKYBLUE (-5800 2425);
FORCEPROP 1 LAST MATERIAL CHIP
J 0
(-6025 2425);
DISPLAY 0.489362 (-6025 2425);
PAINT SKYBLUE (-6025 2425);
FORCEPROP 1 LAST TOLERANCE 1%
J 0
(-6250 2425);
DISPLAY 0.489362 (-6250 2425);
PAINT SKYBLUE (-6250 2425);
FORCEPROP 1 LAST VALUE 1K
J 2
(-6275 2425);
DISPLAY 0.489362 (-6275 2425);
PAINT SKYBLUE (-6275 2425);
FORCEPROP 1 LAST PART_NUMBER TMP_QCS21002FB24
J 0
(-6325 2475);
DISPLAY 0.489362 (-6325 2475);
PAINT SKYBLUE (-6325 2475);
FORCEPROP 1 LAST PACK_TYPE 0402LF
J 0
(-6175 2425);
DISPLAY 0.489362 (-6175 2425);
PAINT SKYBLUE (-6175 2425);
FORCEPROP 2 LAST CDS_LIB pure_quanta
J 0
(-6075 2400);
DISPLAY INVISIBLE (-6075 2400);
FORCEPROP 1 LAST PATH I180
J 0
(-6125 2550);
DISPLAY 0.978723 (-6125 2550);
PAINT WHITE (-6125 2550);
DISPLAY INVISIBLE (-6125 2550);
FORCEADD Q_RES..1
(-5400 1975);
FORCEPROP 1 LAST LOCATION PR180
J 0
(-5450 2025);
DISPLAY 0.489362 (-5450 2025);
PAINT SKYBLUE (-5450 2025);
FORCEPROP 0 LAST $SEC 1
J 0
(-5650 2075);
DISPLAY 0.680851 (-5650 2075);
PAINT MONO (-5650 2075);
DISPLAY INVISIBLE (-5650 2075);
FORCEPROP 0 LAST CDS_SEC 1
J 0
(-5650 2075);
DISPLAY 1.021277 (-5650 2075);
DISPLAY INVISIBLE (-5650 2075);
FORCEPROP 1 LASTPIN (-5500 1975) $PN 1
J 0
(-5488 1987);
DISPLAY 0.489362 (-5488 1987);
PAINT MONO (-5488 1987);
FORCEPROP 1 LASTPIN (-5300 1975) $PN 2
J 0
(-5338 1987);
DISPLAY 0.489362 (-5338 1987);
PAINT MONO (-5338 1987);
FORCEPROP 1 LAST WATTAGE 1/16W
J 2
(-5125 2000);
DISPLAY 0.489362 (-5125 2000);
PAINT SKYBLUE (-5125 2000);
FORCEPROP 1 LAST MATERIAL CHIP
J 0
(-5350 2000);
DISPLAY 0.489362 (-5350 2000);
PAINT SKYBLUE (-5350 2000);
FORCEPROP 1 LAST TOLERANCE 1%
J 0
(-5275 1875);
DISPLAY 0.489362 (-5275 1875);
PAINT SKYBLUE (-5275 1875);
FORCEPROP 1 LAST VALUE 1K
J 2
(-5525 2000);
DISPLAY 0.489362 (-5525 2000);
PAINT SKYBLUE (-5525 2000);
FORCEPROP 1 LAST PART_NUMBER TMP_QCS21002FB24
J 0
(-5775 1925);
DISPLAY 0.489362 (-5775 1925);
PAINT SKYBLUE (-5775 1925);
FORCEPROP 1 LAST PACK_TYPE 0402LF
J 0
(-5325 1925);
DISPLAY 0.489362 (-5325 1925);
PAINT SKYBLUE (-5325 1925);
FORCEPROP 2 LAST CDS_LIB pure_quanta
J 0
(-5400 1975);
DISPLAY INVISIBLE (-5400 1975);
FORCEPROP 1 LAST PATH I181
J 0
(-5450 2125);
DISPLAY 0.978723 (-5450 2125);
PAINT WHITE (-5450 2125);
DISPLAY INVISIBLE (-5450 2125);
FORCEADD UNIVERSAL_GND..1
R 1
(-5275 1725);
FORCEPROP 3 LASTPIN (-5325 1725) SIG_NAME GND\g
J 0
(-5315 1735);
DISPLAY 0.659574 (-5315 1735);
PAINT MONO (-5315 1735);
DISPLAY INVISIBLE (-5315 1735);
FORCEPROP 2 LAST CDS_LIB pure_quanta_power
J 0
(-5275 1725);
DISPLAY INVISIBLE (-5275 1725);
FORCEPROP 1 LAST PATH I182
R 1
J 0
(-5275 1800);
DISPLAY 0.872340 (-5275 1800);
PAINT AQUA (-5275 1800);
DISPLAY INVISIBLE (-5275 1800);
FORCEPROP 1 LAST HDL_POWER GND
R 1
J 1
(-5200 1750);
DISPLAY 0.872340 (-5200 1750);
PAINT GREEN (-5200 1750);
DISPLAY INVISIBLE (-5200 1750);
FORCEADD OFFPAGE..4
R 2
(-8900 5650);
FORCEPROP 2 LAST $XR0 54 
J 0
(-9121 5650);
DISPLAY 0.638298 (-9121 5650);
PAINT MONO (-9121 5650);
FORCEPROP 2 LAST CDS_LIB standard
J 0
(-8900 5650);
DISPLAY INVISIBLE (-8900 5650);
FORCEPROP 1 LAST OFFPAGE TRUE
J 2
(-9225 5525);
DISPLAY 0.872340 (-9225 5525);
PAINT GREEN (-9225 5525);
DISPLAY INVISIBLE (-9225 5525);
FORCEPROP 1 LAST COMMENT_BODY TRUE
J 2
(-8875 5550);
DISPLAY 0.872340 (-8875 5550);
PAINT GREEN (-8875 5550);
DISPLAY INVISIBLE (-8875 5550);
FORCEPROP 2 LAST PATH I183
J 0
(-8850 5725);
DISPLAY 1.021277 (-8850 5725);
DISPLAY INVISIBLE (-8850 5725);
FORCEADD OFFPAGE..4
R 2
(-8900 5500);
FORCEPROP 2 LAST $XR0 54 
J 0
(-9121 5500);
DISPLAY 0.638298 (-9121 5500);
PAINT MONO (-9121 5500);
FORCEPROP 2 LAST CDS_LIB standard
J 0
(-8900 5500);
DISPLAY INVISIBLE (-8900 5500);
FORCEPROP 1 LAST OFFPAGE TRUE
J 2
(-9225 5375);
DISPLAY 0.872340 (-9225 5375);
PAINT GREEN (-9225 5375);
DISPLAY INVISIBLE (-9225 5375);
FORCEPROP 1 LAST COMMENT_BODY TRUE
J 2
(-8875 5400);
DISPLAY 0.872340 (-8875 5400);
PAINT GREEN (-8875 5400);
DISPLAY INVISIBLE (-8875 5400);
FORCEPROP 2 LAST PATH I184
J 0
(-8850 5575);
DISPLAY 1.021277 (-8850 5575);
DISPLAY INVISIBLE (-8850 5575);
FORCEADD Q_RES..2
(-8525 5025);
FORCEPROP 1 LAST LOCATION PR150
J 0
(-8480 5150);
DISPLAY 0.489362 (-8480 5150);
PAINT SKYBLUE (-8480 5150);
FORCEPROP 0 LAST $SEC 1
J 0
(-8475 5175);
DISPLAY 0.680851 (-8475 5175);
PAINT MONO (-8475 5175);
DISPLAY INVISIBLE (-8475 5175);
FORCEPROP 0 LAST CDS_SEC 1
J 0
(-8475 5175);
DISPLAY 1.021277 (-8475 5175);
DISPLAY INVISIBLE (-8475 5175);
FORCEPROP 1 LASTPIN (-8525 5125) $PN 1
J 0
(-8520 5087);
DISPLAY 0.489362 (-8520 5087);
PAINT MONO (-8520 5087);
FORCEPROP 1 LASTPIN (-8525 4925) $PN 2
J 0
(-8520 4935);
DISPLAY 0.489362 (-8520 4935);
PAINT MONO (-8520 4935);
FORCEPROP 1 LAST WATTAGE 1/16W
J 0
(-8475 5000);
DISPLAY 0.489362 (-8475 5000);
PAINT SKYBLUE (-8475 5000);
FORCEPROP 1 LAST MATERIAL CHIP
J 0
(-8475 4950);
DISPLAY 0.489362 (-8475 4950);
PAINT SKYBLUE (-8475 4950);
FORCEPROP 1 LAST TOLERANCE 5%
J 0
(-8475 5050);
DISPLAY 0.489362 (-8475 5050);
PAINT SKYBLUE (-8475 5050);
FORCEPROP 1 LAST VALUE 1K
J 0
(-8475 5100);
DISPLAY 0.489362 (-8475 5100);
PAINT SKYBLUE (-8475 5100);
FORCEPROP 1 LAST PACK_TYPE 0402LF
J 0
(-8475 4900);
DISPLAY 0.489362 (-8475 4900);
PAINT SKYBLUE (-8475 4900);
FORCEPROP 2 LAST CDS_LIB pure_quanta
J 0
(-8525 5025);
DISPLAY INVISIBLE (-8525 5025);
FORCEPROP 1 LAST PATH I185
J 0
(-8475 5200);
DISPLAY 0.978723 (-8475 5200);
PAINT WHITE (-8475 5200);
DISPLAY INVISIBLE (-8475 5200);
FORCEPROP 1 LAST PART_NUMBER TMP_QCS21002JB34
J 0
(-8485 4900);
DISPLAY 0.489362 (-8485 4900);
PAINT SKYBLUE (-8485 4900);
DISPLAY INVISIBLE (-8485 4900);
FORCEADD Q_RES..1
(-6125 6375);
FORCEPROP 1 LAST LOCATION PR167
J 0
(-6175 6425);
DISPLAY 0.489362 (-6175 6425);
PAINT SKYBLUE (-6175 6425);
FORCEPROP 0 LAST $SEC 1
J 0
(-6175 6450);
DISPLAY 0.680851 (-6175 6450);
PAINT MONO (-6175 6450);
DISPLAY INVISIBLE (-6175 6450);
FORCEPROP 0 LAST CDS_SEC 1
J 0
(-6175 6450);
DISPLAY 1.021277 (-6175 6450);
DISPLAY INVISIBLE (-6175 6450);
FORCEPROP 1 LASTPIN (-6225 6375) $PN 1
J 0
(-6213 6387);
DISPLAY 0.489362 (-6213 6387);
PAINT MONO (-6213 6387);
FORCEPROP 1 LASTPIN (-6025 6375) $PN 2
J 0
(-6063 6387);
DISPLAY 0.489362 (-6063 6387);
PAINT MONO (-6063 6387);
FORCEPROP 1 LAST WATTAGE 1/16W
J 0
(-6025 6325);
DISPLAY 0.489362 (-6025 6325);
PAINT SKYBLUE (-6025 6325);
FORCEPROP 1 LAST MATERIAL CHIP
J 0
(-6450 6275);
DISPLAY 0.489362 (-6450 6275);
PAINT SKYBLUE (-6450 6275);
FORCEPROP 1 LAST TOLERANCE 1%
J 0
(-6000 6400);
DISPLAY 0.489362 (-6000 6400);
PAINT SKYBLUE (-6000 6400);
FORCEPROP 1 LAST VALUE 1K
J 2
(-6275 6400);
DISPLAY 0.489362 (-6275 6400);
PAINT SKYBLUE (-6275 6400);
FORCEPROP 1 LAST PART_NUMBER TMP_QCS21002FB24
J 0
(-6450 6325);
DISPLAY 0.489362 (-6450 6325);
PAINT SKYBLUE (-6450 6325);
FORCEPROP 1 LAST PACK_TYPE 0402LF
J 0
(-6025 6275);
DISPLAY 0.489362 (-6025 6275);
PAINT SKYBLUE (-6025 6275);
FORCEPROP 2 LAST CDS_LIB pure_quanta
J 0
(-6125 6375);
DISPLAY INVISIBLE (-6125 6375);
FORCEPROP 1 LAST PATH I186
J 0
(-6175 6525);
DISPLAY 0.978723 (-6175 6525);
PAINT WHITE (-6175 6525);
DISPLAY INVISIBLE (-6175 6525);
FORCEADD Q_RES..1
(-5925 4950);
FORCEPROP 1 LAST LOCATION PR175
J 0
(-5975 5000);
DISPLAY 0.489362 (-5975 5000);
PAINT SKYBLUE (-5975 5000);
FORCEPROP 0 LAST $SEC 1
J 0
(-5975 5025);
DISPLAY 0.680851 (-5975 5025);
PAINT MONO (-5975 5025);
DISPLAY INVISIBLE (-5975 5025);
FORCEPROP 0 LAST CDS_SEC 1
J 0
(-5975 5025);
DISPLAY 1.021277 (-5975 5025);
DISPLAY INVISIBLE (-5975 5025);
FORCEPROP 1 LASTPIN (-6025 4950) $PN 1
J 0
(-6013 4962);
DISPLAY 0.489362 (-6013 4962);
PAINT MONO (-6013 4962);
FORCEPROP 1 LASTPIN (-5825 4950) $PN 2
J 0
(-5863 4962);
DISPLAY 0.489362 (-5863 4962);
PAINT MONO (-5863 4962);
FORCEPROP 1 LAST WATTAGE 1/16W
J 0
(-5825 4900);
DISPLAY 0.489362 (-5825 4900);
PAINT SKYBLUE (-5825 4900);
FORCEPROP 1 LAST MATERIAL CHIP
J 0
(-6175 4875);
DISPLAY 0.489362 (-6175 4875);
PAINT SKYBLUE (-6175 4875);
FORCEPROP 1 LAST TOLERANCE 5%
J 0
(-5800 4975);
DISPLAY 0.489362 (-5800 4975);
PAINT SKYBLUE (-5800 4975);
FORCEPROP 1 LAST VALUE 0
J 2
(-6050 4975);
DISPLAY 0.489362 (-6050 4975);
PAINT SKYBLUE (-6050 4975);
FORCEPROP 1 LAST PART_NUMBER CS00002JB38
J 0
(-6175 4900);
DISPLAY 0.489362 (-6175 4900);
PAINT SKYBLUE (-6175 4900);
FORCEPROP 1 LAST PACK_TYPE 0402LF
J 0
(-5825 4875);
DISPLAY 0.489362 (-5825 4875);
PAINT SKYBLUE (-5825 4875);
FORCEPROP 2 LAST CDS_LIB pure_quanta
J 0
(-5925 4950);
DISPLAY INVISIBLE (-5925 4950);
FORCEPROP 1 LAST PATH I187
J 0
(-5975 5100);
DISPLAY 0.978723 (-5975 5100);
PAINT WHITE (-5975 5100);
DISPLAY INVISIBLE (-5975 5100);
FORCEADD Q_CAP..1
(-7550 5025);
FORCEPROP 1 LAST LOCATION PC297
J 0
(-7500 5125);
DISPLAY 0.489362 (-7500 5125);
PAINT SKYBLUE (-7500 5125);
FORCEPROP 0 LAST $SEC 1
J 0
(-7500 5150);
DISPLAY 0.680851 (-7500 5150);
PAINT MONO (-7500 5150);
DISPLAY INVISIBLE (-7500 5150);
FORCEPROP 0 LAST CDS_SEC 1
J 0
(-7500 5150);
DISPLAY 1.021277 (-7500 5150);
DISPLAY INVISIBLE (-7500 5150);
FORCEPROP 1 LASTPIN (-7550 5125) $PN 1
J 0
(-7540 5105);
DISPLAY 0.489362 (-7540 5105);
PAINT MONO (-7540 5105);
FORCEPROP 1 LASTPIN (-7550 4925) $PN 2
J 0
(-7540 4905);
DISPLAY 0.489362 (-7540 4905);
PAINT MONO (-7540 4905);
FORCEPROP 1 LAST MATERIAL EMPTY
J 0
(-7500 4925);
DISPLAY 0.489362 (-7500 4925);
PAINT RED (-7500 4925);
FORCEPROP 1 LAST TOLERANCE 5%
J 0
(-7500 4975);
DISPLAY 0.489362 (-7500 4975);
PAINT SKYBLUE (-7500 4975);
FORCEPROP 1 LAST VALUE 10PF
J 0
(-7500 5075);
DISPLAY 0.489362 (-7500 5075);
PAINT SKYBLUE (-7500 5075);
FORCEPROP 1 LAST PART_NUMBER CH01006JB08
J 0
(-7500 4875);
DISPLAY 0.489362 (-7500 4875);
PAINT SKYBLUE (-7500 4875);
FORCEPROP 1 LAST VOLTAGE 50V
J 0
(-7500 5025);
DISPLAY 0.489362 (-7500 5025);
PAINT SKYBLUE (-7500 5025);
FORCEPROP 1 LAST PACK_TYPE 0402
J 0
(-7500 4825);
DISPLAY 0.489362 (-7500 4825);
PAINT SKYBLUE (-7500 4825);
FORCEPROP 2 LAST CDS_LIB pure_quanta
J 0
(-7550 5025);
DISPLAY INVISIBLE (-7550 5025);
FORCEPROP 1 LAST PATH I214
J 0
(-7500 5175);
DISPLAY 0.978723 (-7500 5175);
PAINT WHITE (-7500 5175);
DISPLAY INVISIBLE (-7500 5175);
FORCEADD Q_CAP..1
(-7825 5025);
FORCEPROP 1 LAST LOCATION PC296
J 0
(-7775 5125);
DISPLAY 0.489362 (-7775 5125);
PAINT SKYBLUE (-7775 5125);
FORCEPROP 0 LAST $SEC 1
J 0
(-7775 5150);
DISPLAY 0.680851 (-7775 5150);
PAINT MONO (-7775 5150);
DISPLAY INVISIBLE (-7775 5150);
FORCEPROP 0 LAST CDS_SEC 1
J 0
(-7775 5150);
DISPLAY 1.021277 (-7775 5150);
DISPLAY INVISIBLE (-7775 5150);
FORCEPROP 1 LASTPIN (-7825 5125) $PN 1
J 0
(-7815 5105);
DISPLAY 0.489362 (-7815 5105);
PAINT MONO (-7815 5105);
FORCEPROP 1 LASTPIN (-7825 4925) $PN 2
J 0
(-7815 4905);
DISPLAY 0.489362 (-7815 4905);
PAINT MONO (-7815 4905);
FORCEPROP 1 LAST MATERIAL EMPTY
J 0
(-7775 4925);
DISPLAY 0.489362 (-7775 4925);
PAINT RED (-7775 4925);
FORCEPROP 1 LAST TOLERANCE 5%
J 0
(-7775 4975);
DISPLAY 0.489362 (-7775 4975);
PAINT SKYBLUE (-7775 4975);
FORCEPROP 1 LAST VALUE 10PF
J 0
(-7775 5075);
DISPLAY 0.489362 (-7775 5075);
PAINT SKYBLUE (-7775 5075);
FORCEPROP 1 LAST VOLTAGE 50V
J 0
(-7775 5025);
DISPLAY 0.489362 (-7775 5025);
PAINT SKYBLUE (-7775 5025);
FORCEPROP 1 LAST PACK_TYPE 0402
J 0
(-7775 4825);
DISPLAY 0.489362 (-7775 4825);
PAINT SKYBLUE (-7775 4825);
FORCEPROP 2 LAST CDS_LIB pure_quanta
J 0
(-7825 5025);
DISPLAY INVISIBLE (-7825 5025);
FORCEPROP 1 LAST PATH I215
J 0
(-7775 5175);
DISPLAY 0.978723 (-7775 5175);
PAINT WHITE (-7775 5175);
DISPLAY INVISIBLE (-7775 5175);
FORCEPROP 1 LAST PART_NUMBER CH01006JB08
J 0
(-7775 4875);
DISPLAY 0.489362 (-7775 4875);
PAINT SKYBLUE (-7775 4875);
DISPLAY INVISIBLE (-7775 4875);
FORCEADD UNIVERSAL_GND..1
(-8050 4775);
FORCEPROP 3 LASTPIN (-8050 4825) SIG_NAME GND\g
J 0
(-8040 4835);
DISPLAY 0.659574 (-8040 4835);
PAINT MONO (-8040 4835);
DISPLAY INVISIBLE (-8040 4835);
FORCEPROP 2 LAST CDS_LIB pure_quanta_power
J 0
(-8050 4775);
DISPLAY INVISIBLE (-8050 4775);
FORCEPROP 1 LAST PATH I216
J 0
(-7975 4775);
DISPLAY 0.872340 (-7975 4775);
PAINT AQUA (-7975 4775);
DISPLAY INVISIBLE (-7975 4775);
FORCEPROP 1 LAST HDL_POWER GND
J 1
(-8025 4700);
DISPLAY 0.872340 (-8025 4700);
PAINT GREEN (-8025 4700);
DISPLAY INVISIBLE (-8025 4700);
FORCEADD Q_CAP..1
(-8050 5025);
FORCEPROP 1 LAST LOCATION PC295
J 0
(-8000 5125);
DISPLAY 0.489362 (-8000 5125);
PAINT SKYBLUE (-8000 5125);
FORCEPROP 0 LAST $SEC 1
J 0
(-8000 5150);
DISPLAY 0.680851 (-8000 5150);
PAINT MONO (-8000 5150);
DISPLAY INVISIBLE (-8000 5150);
FORCEPROP 0 LAST CDS_SEC 1
J 0
(-8000 5150);
DISPLAY 1.021277 (-8000 5150);
DISPLAY INVISIBLE (-8000 5150);
FORCEPROP 1 LASTPIN (-8050 5125) $PN 1
J 0
(-8040 5105);
DISPLAY 0.489362 (-8040 5105);
PAINT MONO (-8040 5105);
FORCEPROP 1 LASTPIN (-8050 4925) $PN 2
J 0
(-8040 4905);
DISPLAY 0.489362 (-8040 4905);
PAINT MONO (-8040 4905);
FORCEPROP 1 LAST MATERIAL EMPTY
J 0
(-8000 4925);
DISPLAY 0.489362 (-8000 4925);
PAINT RED (-8000 4925);
FORCEPROP 1 LAST TOLERANCE 5%
J 0
(-8000 4975);
DISPLAY 0.489362 (-8000 4975);
PAINT SKYBLUE (-8000 4975);
FORCEPROP 1 LAST VALUE 10PF
J 0
(-8000 5075);
DISPLAY 0.489362 (-8000 5075);
PAINT SKYBLUE (-8000 5075);
FORCEPROP 1 LAST VOLTAGE 50V
J 0
(-8000 5025);
DISPLAY 0.489362 (-8000 5025);
PAINT SKYBLUE (-8000 5025);
FORCEPROP 1 LAST PACK_TYPE 0402
J 0
(-8000 4825);
DISPLAY 0.489362 (-8000 4825);
PAINT SKYBLUE (-8000 4825);
FORCEPROP 2 LAST CDS_LIB pure_quanta
J 0
(-8050 5025);
DISPLAY INVISIBLE (-8050 5025);
FORCEPROP 1 LAST PATH I217
J 0
(-8000 5175);
DISPLAY 0.978723 (-8000 5175);
PAINT WHITE (-8000 5175);
DISPLAY INVISIBLE (-8000 5175);
FORCEPROP 1 LAST PART_NUMBER CH01006JB08
J 0
(-8000 4875);
DISPLAY 0.489362 (-8000 4875);
PAINT SKYBLUE (-8000 4875);
DISPLAY INVISIBLE (-8000 4875);
FORCEADD OFFPAGE..2
(-2775 2100);
FORCEPROP 2 LAST $XR0 191 
J 0
(-2586 2100);
DISPLAY 0.638298 (-2586 2100);
PAINT MONO (-2586 2100);
FORCEPROP 1 LAST COMMENT_BODY TRUE
J 0
(-2820 2005);
DISPLAY 0.872340 (-2820 2005);
PAINT GREEN (-2820 2005);
DISPLAY INVISIBLE (-2820 2005);
FORCEPROP 1 LAST OFFPAGE TRUE
J 0
(-2450 1975);
DISPLAY 0.872340 (-2450 1975);
PAINT GREEN (-2450 1975);
DISPLAY INVISIBLE (-2450 1975);
FORCEPROP 2 LAST CDS_LIB standard
J 0
(-2775 2100);
DISPLAY INVISIBLE (-2775 2100);
FORCEPROP 2 LAST PATH I218
J 0
(-2575 2150);
DISPLAY 1.021277 (-2575 2150);
DISPLAY INVISIBLE (-2575 2150);
FORCEADD OFFPAGE..4
(-2775 2000);
FORCEPROP 2 LAST $XR0 191 
J 0
(-2589 2000);
DISPLAY 0.638298 (-2589 2000);
PAINT MONO (-2589 2000);
FORCEPROP 1 LAST COMMENT_BODY TRUE
J 0
(-2800 1900);
DISPLAY 0.872340 (-2800 1900);
PAINT GREEN (-2800 1900);
DISPLAY INVISIBLE (-2800 1900);
FORCEPROP 1 LAST OFFPAGE TRUE
J 0
(-2450 1875);
DISPLAY 0.872340 (-2450 1875);
PAINT GREEN (-2450 1875);
DISPLAY INVISIBLE (-2450 1875);
FORCEPROP 2 LAST CDS_LIB standard
J 0
(-2775 2000);
DISPLAY INVISIBLE (-2775 2000);
FORCEPROP 2 LAST PATH I219
J 0
(-2575 2050);
DISPLAY 1.021277 (-2575 2050);
DISPLAY INVISIBLE (-2575 2050);
FORCEADD OFFPAGE..2
(-2800 1800);
FORCEPROP 2 LAST $XR0 191 
J 0
(-2611 1800);
DISPLAY 0.638298 (-2611 1800);
PAINT MONO (-2611 1800);
FORCEPROP 1 LAST COMMENT_BODY TRUE
J 0
(-2845 1705);
DISPLAY 0.872340 (-2845 1705);
PAINT GREEN (-2845 1705);
DISPLAY INVISIBLE (-2845 1705);
FORCEPROP 1 LAST OFFPAGE TRUE
J 0
(-2475 1675);
DISPLAY 0.872340 (-2475 1675);
PAINT GREEN (-2475 1675);
DISPLAY INVISIBLE (-2475 1675);
FORCEPROP 2 LAST CDS_LIB standard
J 0
(-2800 1800);
DISPLAY INVISIBLE (-2800 1800);
FORCEPROP 2 LAST PATH I220
J 0
(-2600 1850);
DISPLAY 1.021277 (-2600 1850);
DISPLAY INVISIBLE (-2600 1850);
FORCEADD OFFPAGE..4
(-2800 1700);
FORCEPROP 2 LAST $XR0 191 
J 0
(-2614 1700);
DISPLAY 0.638298 (-2614 1700);
PAINT MONO (-2614 1700);
FORCEPROP 1 LAST COMMENT_BODY TRUE
J 0
(-2825 1600);
DISPLAY 0.872340 (-2825 1600);
PAINT GREEN (-2825 1600);
DISPLAY INVISIBLE (-2825 1600);
FORCEPROP 1 LAST OFFPAGE TRUE
J 0
(-2475 1575);
DISPLAY 0.872340 (-2475 1575);
PAINT GREEN (-2475 1575);
DISPLAY INVISIBLE (-2475 1575);
FORCEPROP 2 LAST CDS_LIB standard
J 0
(-2800 1700);
DISPLAY INVISIBLE (-2800 1700);
FORCEPROP 2 LAST PATH I221
J 0
(-2600 1750);
DISPLAY 1.021277 (-2600 1750);
DISPLAY INVISIBLE (-2600 1750);
FORCEADD OFFPAGE..4
(-2775 2300);
FORCEPROP 2 LAST $XR0 192 
J 0
(-2589 2300);
DISPLAY 0.638298 (-2589 2300);
PAINT MONO (-2589 2300);
FORCEPROP 2 LAST PATH I222
J 0
(-2575 2350);
DISPLAY 1.021277 (-2575 2350);
DISPLAY INVISIBLE (-2575 2350);
FORCEPROP 2 LAST CDS_LIB standard
J 0
(-2775 2300);
DISPLAY INVISIBLE (-2775 2300);
FORCEPROP 1 LAST OFFPAGE TRUE
J 0
(-2450 2175);
DISPLAY 0.872340 (-2450 2175);
PAINT GREEN (-2450 2175);
DISPLAY INVISIBLE (-2450 2175);
FORCEPROP 1 LAST COMMENT_BODY TRUE
J 0
(-2800 2200);
DISPLAY 0.872340 (-2800 2200);
PAINT GREEN (-2800 2200);
DISPLAY INVISIBLE (-2800 2200);
FORCEADD OFFPAGE..2
(-2775 2400);
FORCEPROP 2 LAST $XR0 192 
J 0
(-2586 2400);
DISPLAY 0.638298 (-2586 2400);
PAINT MONO (-2586 2400);
FORCEPROP 2 LAST PATH I223
J 0
(-2575 2450);
DISPLAY 1.021277 (-2575 2450);
DISPLAY INVISIBLE (-2575 2450);
FORCEPROP 2 LAST CDS_LIB standard
J 0
(-2775 2400);
DISPLAY INVISIBLE (-2775 2400);
FORCEPROP 1 LAST OFFPAGE TRUE
J 0
(-2450 2275);
DISPLAY 0.872340 (-2450 2275);
PAINT GREEN (-2450 2275);
DISPLAY INVISIBLE (-2450 2275);
FORCEPROP 1 LAST COMMENT_BODY TRUE
J 0
(-2820 2305);
DISPLAY 0.872340 (-2820 2305);
PAINT GREEN (-2820 2305);
DISPLAY INVISIBLE (-2820 2305);
FORCEADD OFFPAGE..2
(-2800 5100);
FORCEPROP 2 LAST $XR0 187 
J 0
(-2611 5100);
DISPLAY 0.638298 (-2611 5100);
PAINT MONO (-2611 5100);
FORCEPROP 2 LAST CDS_LIB standard
J 0
(-2800 5100);
DISPLAY INVISIBLE (-2800 5100);
FORCEPROP 1 LAST OFFPAGE TRUE
J 0
(-2475 4975);
DISPLAY 0.872340 (-2475 4975);
PAINT GREEN (-2475 4975);
DISPLAY INVISIBLE (-2475 4975);
FORCEPROP 1 LAST COMMENT_BODY TRUE
J 0
(-2845 5005);
DISPLAY 0.872340 (-2845 5005);
PAINT GREEN (-2845 5005);
DISPLAY INVISIBLE (-2845 5005);
FORCEPROP 2 LAST PATH I224
J 0
(-2600 5150);
DISPLAY 1.021277 (-2600 5150);
DISPLAY INVISIBLE (-2600 5150);
FORCEADD OFFPAGE..4
(-2800 5000);
FORCEPROP 2 LAST $XR0 187 
J 0
(-2614 5000);
DISPLAY 0.638298 (-2614 5000);
PAINT MONO (-2614 5000);
FORCEPROP 2 LAST CDS_LIB standard
J 0
(-2800 5000);
DISPLAY INVISIBLE (-2800 5000);
FORCEPROP 1 LAST OFFPAGE TRUE
J 0
(-2475 4875);
DISPLAY 0.872340 (-2475 4875);
PAINT GREEN (-2475 4875);
DISPLAY INVISIBLE (-2475 4875);
FORCEPROP 1 LAST COMMENT_BODY TRUE
J 0
(-2825 4900);
DISPLAY 0.872340 (-2825 4900);
PAINT GREEN (-2825 4900);
DISPLAY INVISIBLE (-2825 4900);
FORCEPROP 2 LAST PATH I225
J 0
(-2600 5050);
DISPLAY 1.021277 (-2600 5050);
DISPLAY INVISIBLE (-2600 5050);
FORCEADD OFFPAGE..2
(-2775 4800);
FORCEPROP 2 LAST $XR0 187 
J 0
(-2586 4800);
DISPLAY 0.638298 (-2586 4800);
PAINT MONO (-2586 4800);
FORCEPROP 2 LAST CDS_LIB standard
J 0
(-2775 4800);
DISPLAY INVISIBLE (-2775 4800);
FORCEPROP 1 LAST OFFPAGE TRUE
J 0
(-2450 4675);
DISPLAY 0.872340 (-2450 4675);
PAINT GREEN (-2450 4675);
DISPLAY INVISIBLE (-2450 4675);
FORCEPROP 1 LAST COMMENT_BODY TRUE
J 0
(-2820 4705);
DISPLAY 0.872340 (-2820 4705);
PAINT GREEN (-2820 4705);
DISPLAY INVISIBLE (-2820 4705);
FORCEPROP 2 LAST PATH I226
J 0
(-2575 4850);
DISPLAY 1.021277 (-2575 4850);
DISPLAY INVISIBLE (-2575 4850);
FORCEADD OFFPAGE..4
(-2775 4700);
FORCEPROP 2 LAST $XR0 187 
J 0
(-2589 4700);
DISPLAY 0.638298 (-2589 4700);
PAINT MONO (-2589 4700);
FORCEPROP 2 LAST CDS_LIB standard
J 0
(-2775 4700);
DISPLAY INVISIBLE (-2775 4700);
FORCEPROP 1 LAST OFFPAGE TRUE
J 0
(-2450 4575);
DISPLAY 0.872340 (-2450 4575);
PAINT GREEN (-2450 4575);
DISPLAY INVISIBLE (-2450 4575);
FORCEPROP 1 LAST COMMENT_BODY TRUE
J 0
(-2800 4600);
DISPLAY 0.872340 (-2800 4600);
PAINT GREEN (-2800 4600);
DISPLAY INVISIBLE (-2800 4600);
FORCEPROP 2 LAST PATH I227
J 0
(-2575 4750);
DISPLAY 1.021277 (-2575 4750);
DISPLAY INVISIBLE (-2575 4750);
FORCEADD OFFPAGE..4
(-2775 4400);
FORCEPROP 2 LAST $XR0 188 
J 0
(-2589 4400);
DISPLAY 0.638298 (-2589 4400);
PAINT MONO (-2589 4400);
FORCEPROP 1 LAST COMMENT_BODY TRUE
J 0
(-2800 4300);
DISPLAY 0.872340 (-2800 4300);
PAINT GREEN (-2800 4300);
DISPLAY INVISIBLE (-2800 4300);
FORCEPROP 1 LAST OFFPAGE TRUE
J 0
(-2450 4275);
DISPLAY 0.872340 (-2450 4275);
PAINT GREEN (-2450 4275);
DISPLAY INVISIBLE (-2450 4275);
FORCEPROP 2 LAST CDS_LIB standard
J 0
(-2775 4400);
DISPLAY INVISIBLE (-2775 4400);
FORCEPROP 2 LAST PATH I228
J 0
(-2575 4450);
DISPLAY 1.021277 (-2575 4450);
DISPLAY INVISIBLE (-2575 4450);
FORCEADD OFFPAGE..2
(-2775 4500);
FORCEPROP 2 LAST $XR0 188 
J 0
(-2586 4500);
DISPLAY 0.638298 (-2586 4500);
PAINT MONO (-2586 4500);
FORCEPROP 1 LAST COMMENT_BODY TRUE
J 0
(-2820 4405);
DISPLAY 0.872340 (-2820 4405);
PAINT GREEN (-2820 4405);
DISPLAY INVISIBLE (-2820 4405);
FORCEPROP 1 LAST OFFPAGE TRUE
J 0
(-2450 4375);
DISPLAY 0.872340 (-2450 4375);
PAINT GREEN (-2450 4375);
DISPLAY INVISIBLE (-2450 4375);
FORCEPROP 2 LAST CDS_LIB standard
J 0
(-2775 4500);
DISPLAY INVISIBLE (-2775 4500);
FORCEPROP 2 LAST PATH I229
J 0
(-2575 4550);
DISPLAY 1.021277 (-2575 4550);
DISPLAY INVISIBLE (-2575 4550);
FORCEADD Q_RES..1
(-2825 3200);
FORCEPROP 1 LAST LOCATION PR530
J 0
(-2875 3250);
DISPLAY 0.489362 (-2875 3250);
PAINT SKYBLUE (-2875 3250);
FORCEPROP 0 LAST $SEC 1
J 0
(-2875 3275);
DISPLAY 0.680851 (-2875 3275);
PAINT MONO (-2875 3275);
DISPLAY INVISIBLE (-2875 3275);
FORCEPROP 0 LAST CDS_SEC 1
J 0
(-2875 3275);
DISPLAY 1.021277 (-2875 3275);
DISPLAY INVISIBLE (-2875 3275);
FORCEPROP 1 LASTPIN (-2925 3200) $PN 1
J 0
(-2913 3212);
DISPLAY 0.489362 (-2913 3212);
PAINT MONO (-2913 3212);
FORCEPROP 1 LASTPIN (-2725 3200) $PN 2
J 0
(-2763 3212);
DISPLAY 0.489362 (-2763 3212);
PAINT MONO (-2763 3212);
FORCEPROP 1 LAST PACK_TYPE 0402LF
J 0
(-2725 3150);
DISPLAY 0.489362 (-2725 3150);
PAINT SKYBLUE (-2725 3150);
FORCEPROP 1 LAST VALUE 0
J 2
(-2825 3150);
DISPLAY 0.489362 (-2825 3150);
PAINT SKYBLUE (-2825 3150);
FORCEPROP 1 LAST WATTAGE 1/16W
J 2
(-2900 3150);
DISPLAY 0.489362 (-2900 3150);
PAINT SKYBLUE (-2900 3150);
FORCEPROP 1 LAST MATERIAL CHIP
J 0
(-3150 3150);
DISPLAY 0.489362 (-3150 3150);
PAINT SKYBLUE (-3150 3150);
FORCEPROP 1 LAST TOLERANCE 5%
J 0
(-2800 3150);
DISPLAY 0.489362 (-2800 3150);
PAINT SKYBLUE (-2800 3150);
FORCEPROP 1 LAST PART_NUMBER CS00002JB38
J 0
(-3500 3150);
DISPLAY 0.489362 (-3500 3150);
PAINT SKYBLUE (-3500 3150);
FORCEPROP 2 LAST CDS_LIB pure_quanta
J 0
(-2825 3200);
DISPLAY INVISIBLE (-2825 3200);
FORCEPROP 1 LAST PATH I230
J 0
(-2875 3350);
DISPLAY 0.978723 (-2875 3350);
PAINT WHITE (-2875 3350);
DISPLAY INVISIBLE (-2875 3350);
FORCEADD UNIVERSAL_GND..1
(-2500 3075);
FORCEPROP 3 LASTPIN (-2500 3125) SIG_NAME GND\g
J 0
(-2490 3135);
DISPLAY 0.659574 (-2490 3135);
PAINT MONO (-2490 3135);
DISPLAY INVISIBLE (-2490 3135);
FORCEPROP 2 LAST CDS_LIB pure_quanta_power
J 0
(-2500 3075);
DISPLAY INVISIBLE (-2500 3075);
FORCEPROP 1 LAST PATH I231
J 0
(-2425 3075);
DISPLAY 0.872340 (-2425 3075);
PAINT AQUA (-2425 3075);
DISPLAY INVISIBLE (-2425 3075);
FORCEPROP 1 LAST HDL_POWER GND
J 1
(-2475 3000);
DISPLAY 0.872340 (-2475 3000);
PAINT GREEN (-2475 3000);
DISPLAY INVISIBLE (-2475 3000);
FORCEADD UNIVERSAL_GND..1
(-2500 2775);
FORCEPROP 3 LASTPIN (-2500 2825) SIG_NAME GND\g
J 0
(-2490 2835);
DISPLAY 0.659574 (-2490 2835);
PAINT MONO (-2490 2835);
DISPLAY INVISIBLE (-2490 2835);
FORCEPROP 2 LAST CDS_LIB pure_quanta_power
J 0
(-2500 2775);
DISPLAY INVISIBLE (-2500 2775);
FORCEPROP 1 LAST PATH I232
J 0
(-2425 2775);
DISPLAY 0.872340 (-2425 2775);
PAINT AQUA (-2425 2775);
DISPLAY INVISIBLE (-2425 2775);
FORCEPROP 1 LAST HDL_POWER GND
J 1
(-2475 2700);
DISPLAY 0.872340 (-2475 2700);
PAINT GREEN (-2475 2700);
DISPLAY INVISIBLE (-2475 2700);
FORCEADD Q_RES..1
(-2825 2900);
FORCEPROP 1 LAST LOCATION PR436
J 0
(-2875 2950);
DISPLAY 0.489362 (-2875 2950);
PAINT SKYBLUE (-2875 2950);
FORCEPROP 0 LAST $SEC 1
J 0
(-2875 2975);
DISPLAY 0.680851 (-2875 2975);
PAINT MONO (-2875 2975);
DISPLAY INVISIBLE (-2875 2975);
FORCEPROP 0 LAST CDS_SEC 1
J 0
(-2875 2975);
DISPLAY 1.021277 (-2875 2975);
DISPLAY INVISIBLE (-2875 2975);
FORCEPROP 1 LASTPIN (-2925 2900) $PN 1
J 0
(-2913 2912);
DISPLAY 0.489362 (-2913 2912);
PAINT MONO (-2913 2912);
FORCEPROP 1 LASTPIN (-2725 2900) $PN 2
J 0
(-2763 2912);
DISPLAY 0.489362 (-2763 2912);
PAINT MONO (-2763 2912);
FORCEPROP 1 LAST WATTAGE 1/16W
J 2
(-2900 2850);
DISPLAY 0.489362 (-2900 2850);
PAINT SKYBLUE (-2900 2850);
FORCEPROP 1 LAST MATERIAL CHIP
J 0
(-3150 2850);
DISPLAY 0.489362 (-3150 2850);
PAINT SKYBLUE (-3150 2850);
FORCEPROP 1 LAST TOLERANCE 5%
J 0
(-2800 2850);
DISPLAY 0.489362 (-2800 2850);
PAINT SKYBLUE (-2800 2850);
FORCEPROP 1 LAST VALUE 0
J 2
(-2825 2850);
DISPLAY 0.489362 (-2825 2850);
PAINT SKYBLUE (-2825 2850);
FORCEPROP 1 LAST PART_NUMBER CS00002JB38
J 0
(-3500 2850);
DISPLAY 0.489362 (-3500 2850);
PAINT SKYBLUE (-3500 2850);
FORCEPROP 1 LAST PACK_TYPE 0402LF
J 0
(-2725 2850);
DISPLAY 0.489362 (-2725 2850);
PAINT SKYBLUE (-2725 2850);
FORCEPROP 2 LAST CDS_LIB pure_quanta
J 0
(-2825 2900);
DISPLAY INVISIBLE (-2825 2900);
FORCEPROP 1 LAST PATH I233
J 0
(-2875 3050);
DISPLAY 0.978723 (-2875 3050);
PAINT WHITE (-2875 3050);
DISPLAY INVISIBLE (-2875 3050);
FORCEADD OFFPAGE..2
(-2800 4200);
FORCEPROP 2 LAST $XR0 188 
J 0
(-2611 4200);
DISPLAY 0.638298 (-2611 4200);
PAINT MONO (-2611 4200);
FORCEPROP 2 LAST CDS_LIB standard
J 0
(-2800 4200);
DISPLAY INVISIBLE (-2800 4200);
FORCEPROP 1 LAST OFFPAGE TRUE
J 0
(-2475 4075);
DISPLAY 0.872340 (-2475 4075);
PAINT GREEN (-2475 4075);
DISPLAY INVISIBLE (-2475 4075);
FORCEPROP 1 LAST COMMENT_BODY TRUE
J 0
(-2845 4105);
DISPLAY 0.872340 (-2845 4105);
PAINT GREEN (-2845 4105);
DISPLAY INVISIBLE (-2845 4105);
FORCEPROP 2 LAST PATH I234
J 0
(-2600 4250);
DISPLAY 1.021277 (-2600 4250);
DISPLAY INVISIBLE (-2600 4250);
FORCEADD OFFPAGE..4
(-2800 4100);
FORCEPROP 2 LAST $XR0 188 
J 0
(-2614 4100);
DISPLAY 0.638298 (-2614 4100);
PAINT MONO (-2614 4100);
FORCEPROP 2 LAST CDS_LIB standard
J 0
(-2800 4100);
DISPLAY INVISIBLE (-2800 4100);
FORCEPROP 1 LAST OFFPAGE TRUE
J 0
(-2475 3975);
DISPLAY 0.872340 (-2475 3975);
PAINT GREEN (-2475 3975);
DISPLAY INVISIBLE (-2475 3975);
FORCEPROP 1 LAST COMMENT_BODY TRUE
J 0
(-2825 4000);
DISPLAY 0.872340 (-2825 4000);
PAINT GREEN (-2825 4000);
DISPLAY INVISIBLE (-2825 4000);
FORCEPROP 2 LAST PATH I235
J 0
(-2600 4150);
DISPLAY 1.021277 (-2600 4150);
DISPLAY INVISIBLE (-2600 4150);
FORCEADD OFFPAGE..4
(-2800 3800);
FORCEPROP 2 LAST $XR0 189 
J 0
(-2614 3800);
DISPLAY 0.638298 (-2614 3800);
PAINT MONO (-2614 3800);
FORCEPROP 2 LAST CDS_LIB standard
J 0
(-2800 3800);
DISPLAY INVISIBLE (-2800 3800);
FORCEPROP 1 LAST OFFPAGE TRUE
J 0
(-2475 3675);
DISPLAY 0.872340 (-2475 3675);
PAINT GREEN (-2475 3675);
DISPLAY INVISIBLE (-2475 3675);
FORCEPROP 1 LAST COMMENT_BODY TRUE
J 0
(-2825 3700);
DISPLAY 0.872340 (-2825 3700);
PAINT GREEN (-2825 3700);
DISPLAY INVISIBLE (-2825 3700);
FORCEPROP 2 LAST PATH I236
J 0
(-2600 3850);
DISPLAY 1.021277 (-2600 3850);
DISPLAY INVISIBLE (-2600 3850);
FORCEADD OFFPAGE..2
(-2800 3900);
FORCEPROP 2 LAST $XR0 189 
J 0
(-2611 3900);
DISPLAY 0.638298 (-2611 3900);
PAINT MONO (-2611 3900);
FORCEPROP 2 LAST CDS_LIB standard
J 0
(-2800 3900);
DISPLAY INVISIBLE (-2800 3900);
FORCEPROP 1 LAST OFFPAGE TRUE
J 0
(-2475 3775);
DISPLAY 0.872340 (-2475 3775);
PAINT GREEN (-2475 3775);
DISPLAY INVISIBLE (-2475 3775);
FORCEPROP 1 LAST COMMENT_BODY TRUE
J 0
(-2845 3805);
DISPLAY 0.872340 (-2845 3805);
PAINT GREEN (-2845 3805);
DISPLAY INVISIBLE (-2845 3805);
FORCEPROP 2 LAST PATH I237
J 0
(-2600 3950);
DISPLAY 1.021277 (-2600 3950);
DISPLAY INVISIBLE (-2600 3950);
FORCEADD OFFPAGE..2
(-2800 3600);
FORCEPROP 2 LAST $XR0 189 
J 0
(-2611 3600);
DISPLAY 0.638298 (-2611 3600);
PAINT MONO (-2611 3600);
FORCEPROP 2 LAST CDS_LIB standard
J 0
(-2800 3600);
DISPLAY INVISIBLE (-2800 3600);
FORCEPROP 1 LAST OFFPAGE TRUE
J 0
(-2475 3475);
DISPLAY 0.872340 (-2475 3475);
PAINT GREEN (-2475 3475);
DISPLAY INVISIBLE (-2475 3475);
FORCEPROP 1 LAST COMMENT_BODY TRUE
J 0
(-2845 3505);
DISPLAY 0.872340 (-2845 3505);
PAINT GREEN (-2845 3505);
DISPLAY INVISIBLE (-2845 3505);
FORCEPROP 2 LAST PATH I238
J 0
(-2600 3650);
DISPLAY 1.021277 (-2600 3650);
DISPLAY INVISIBLE (-2600 3650);
FORCEADD OFFPAGE..4
(-2800 3500);
FORCEPROP 2 LAST $XR0 189 
J 0
(-2614 3500);
DISPLAY 0.638298 (-2614 3500);
PAINT MONO (-2614 3500);
FORCEPROP 2 LAST CDS_LIB standard
J 0
(-2800 3500);
DISPLAY INVISIBLE (-2800 3500);
FORCEPROP 1 LAST OFFPAGE TRUE
J 0
(-2475 3375);
DISPLAY 0.872340 (-2475 3375);
PAINT GREEN (-2475 3375);
DISPLAY INVISIBLE (-2475 3375);
FORCEPROP 1 LAST COMMENT_BODY TRUE
J 0
(-2825 3400);
DISPLAY 0.872340 (-2825 3400);
PAINT GREEN (-2825 3400);
DISPLAY INVISIBLE (-2825 3400);
FORCEPROP 2 LAST PATH I239
J 0
(-2600 3550);
DISPLAY 1.021277 (-2600 3550);
DISPLAY INVISIBLE (-2600 3550);
FORCEADD UNIVERSAL_GND..1
(-2500 2475);
FORCEPROP 3 LASTPIN (-2500 2525) SIG_NAME GND\g
J 0
(-2490 2535);
DISPLAY 0.659574 (-2490 2535);
PAINT MONO (-2490 2535);
DISPLAY INVISIBLE (-2490 2535);
FORCEPROP 2 LAST CDS_LIB pure_quanta_power
J 0
(-2500 2475);
DISPLAY INVISIBLE (-2500 2475);
FORCEPROP 1 LAST PATH I240
J 0
(-2425 2475);
DISPLAY 0.872340 (-2425 2475);
PAINT AQUA (-2425 2475);
DISPLAY INVISIBLE (-2425 2475);
FORCEPROP 1 LAST HDL_POWER GND
J 1
(-2475 2400);
DISPLAY 0.872340 (-2475 2400);
PAINT GREEN (-2475 2400);
DISPLAY INVISIBLE (-2475 2400);
FORCEADD Q_RES..1
(-2825 2600);
FORCEPROP 1 LAST LOCATION PR437
J 0
(-2875 2650);
DISPLAY 0.489362 (-2875 2650);
PAINT SKYBLUE (-2875 2650);
FORCEPROP 0 LAST $SEC 1
J 0
(-2875 2675);
DISPLAY 0.680851 (-2875 2675);
PAINT MONO (-2875 2675);
DISPLAY INVISIBLE (-2875 2675);
FORCEPROP 0 LAST CDS_SEC 1
J 0
(-2875 2675);
DISPLAY 0.680851 (-2875 2675);
DISPLAY INVISIBLE (-2875 2675);
FORCEPROP 1 LASTPIN (-2925 2600) $PN 1
J 0
(-2913 2612);
DISPLAY 0.787234 (-2913 2612);
PAINT MONO (-2913 2612);
DISPLAY INVISIBLE (-2913 2612);
FORCEPROP 1 LASTPIN (-2725 2600) $PN 2
J 0
(-2763 2612);
DISPLAY 0.787234 (-2763 2612);
PAINT MONO (-2763 2612);
DISPLAY INVISIBLE (-2763 2612);
FORCEPROP 1 LAST WATTAGE 1/16W
J 2
(-2900 2550);
DISPLAY 0.489362 (-2900 2550);
PAINT SKYBLUE (-2900 2550);
FORCEPROP 1 LAST MATERIAL CHIP
J 0
(-3150 2550);
DISPLAY 0.489362 (-3150 2550);
PAINT SKYBLUE (-3150 2550);
FORCEPROP 1 LAST TOLERANCE 5%
J 0
(-2800 2550);
DISPLAY 0.489362 (-2800 2550);
PAINT SKYBLUE (-2800 2550);
FORCEPROP 1 LAST VALUE 0
J 2
(-2825 2550);
DISPLAY 0.489362 (-2825 2550);
PAINT SKYBLUE (-2825 2550);
FORCEPROP 1 LAST PART_NUMBER CS00002JB38
J 0
(-3500 2550);
DISPLAY 0.489362 (-3500 2550);
PAINT SKYBLUE (-3500 2550);
FORCEPROP 1 LAST PACK_TYPE 0402LF
J 0
(-2725 2550);
DISPLAY 0.489362 (-2725 2550);
PAINT SKYBLUE (-2725 2550);
FORCEPROP 2 LAST CDS_LIB pure_quanta
J 0
(-2825 2600);
DISPLAY INVISIBLE (-2825 2600);
FORCEPROP 1 LAST PATH I241
J 0
(-2875 2750);
DISPLAY 0.978723 (-2875 2750);
PAINT WHITE (-2875 2750);
DISPLAY INVISIBLE (-2875 2750);
FORCEADD UNIVERSAL_GND..1
(-5625 250);
FORCEPROP 3 LASTPIN (-5625 300) SIG_NAME GND\g
J 0
(-5615 310);
DISPLAY 0.659574 (-5615 310);
PAINT MONO (-5615 310);
DISPLAY INVISIBLE (-5615 310);
FORCEPROP 2 LAST CDS_LIB pure_quanta_power
J 0
(-5625 250);
DISPLAY INVISIBLE (-5625 250);
FORCEPROP 1 LAST PATH I242
J 0
(-5550 250);
DISPLAY 0.872340 (-5550 250);
PAINT AQUA (-5550 250);
DISPLAY INVISIBLE (-5550 250);
FORCEPROP 1 LAST HDL_POWER GND
J 1
(-5600 175);
DISPLAY 0.872340 (-5600 175);
PAINT GREEN (-5600 175);
DISPLAY INVISIBLE (-5600 175);
FORCEADD Q_RES..2
(-5625 450);
FORCEPROP 1 LAST LOCATION PR602
J 0
(-5575 575);
DISPLAY 0.489362 (-5575 575);
PAINT SKYBLUE (-5575 575);
FORCEPROP 0 LAST $SEC 1
J 0
(-5575 600);
DISPLAY 0.680851 (-5575 600);
PAINT MONO (-5575 600);
DISPLAY INVISIBLE (-5575 600);
FORCEPROP 0 LAST CDS_SEC 1
J 0
(-5575 600);
DISPLAY 0.680851 (-5575 600);
DISPLAY INVISIBLE (-5575 600);
FORCEPROP 1 LASTPIN (-5625 550) $PN 1
J 0
(-5620 512);
DISPLAY 0.787234 (-5620 512);
PAINT MONO (-5620 512);
DISPLAY INVISIBLE (-5620 512);
FORCEPROP 1 LASTPIN (-5625 350) $PN 2
J 0
(-5620 360);
DISPLAY 0.787234 (-5620 360);
PAINT MONO (-5620 360);
DISPLAY INVISIBLE (-5620 360);
FORCEPROP 1 LAST WATTAGE 1/16W
J 0
(-5575 425);
DISPLAY 0.489362 (-5575 425);
PAINT SKYBLUE (-5575 425);
FORCEPROP 1 LAST MATERIAL EMPTY
J 0
(-5575 375);
DISPLAY 0.489362 (-5575 375);
PAINT RED (-5575 375);
FORCEPROP 1 LAST TOLERANCE 1%
J 0
(-5575 475);
DISPLAY 0.489362 (-5575 475);
PAINT SKYBLUE (-5575 475);
FORCEPROP 1 LAST VALUE 4.99K
J 0
(-5575 525);
DISPLAY 0.489362 (-5575 525);
PAINT SKYBLUE (-5575 525);
FORCEPROP 1 LAST PART_NUMBER CS24992FB07
J 0
(-5575 325);
DISPLAY 0.489362 (-5575 325);
PAINT SKYBLUE (-5575 325);
FORCEPROP 1 LAST PACK_TYPE 0402LF
J 0
(-5575 275);
DISPLAY 0.489362 (-5575 275);
PAINT SKYBLUE (-5575 275);
FORCEPROP 2 LAST CDS_LIB pure_quanta
J 0
(-5625 450);
DISPLAY INVISIBLE (-5625 450);
FORCEPROP 1 LAST PATH I243
J 0
(-5575 625);
DISPLAY 0.978723 (-5575 625);
PAINT WHITE (-5575 625);
DISPLAY INVISIBLE (-5575 625);
FORCEADD Q_RES..2
(-7100 1375);
FORCEPROP 1 LAST LOCATION PR159
J 0
(-7050 1425);
DISPLAY 0.489362 (-7050 1425);
PAINT SKYBLUE (-7050 1425);
FORCEPROP 0 LAST $SEC 1
J 0
(-7050 1450);
DISPLAY 0.680851 (-7050 1450);
PAINT MONO (-7050 1450);
DISPLAY INVISIBLE (-7050 1450);
FORCEPROP 0 LAST CDS_SEC 1
J 0
(-7050 1450);
DISPLAY 1.021277 (-7050 1450);
DISPLAY INVISIBLE (-7050 1450);
FORCEPROP 1 LASTPIN (-7100 1475) $PN 1
J 0
(-7095 1437);
DISPLAY 0.489362 (-7095 1437);
PAINT MONO (-7095 1437);
FORCEPROP 1 LASTPIN (-7100 1275) $PN 2
J 0
(-7095 1285);
DISPLAY 0.489362 (-7095 1285);
PAINT MONO (-7095 1285);
FORCEPROP 1 LAST WATTAGE 1/16W
J 0
(-7050 1350);
DISPLAY 0.489362 (-7050 1350);
PAINT SKYBLUE (-7050 1350);
FORCEPROP 1 LAST MATERIAL CHIP
J 0
(-7050 1325);
DISPLAY 0.489362 (-7050 1325);
PAINT SKYBLUE (-7050 1325);
FORCEPROP 1 LAST TOLERANCE 1%
J 0
(-7050 1375);
DISPLAY 0.489362 (-7050 1375);
PAINT SKYBLUE (-7050 1375);
FORCEPROP 1 LAST VALUE 6.65K
J 0
(-7050 1400);
DISPLAY 0.489362 (-7050 1400);
PAINT SKYBLUE (-7050 1400);
FORCEPROP 1 LAST PART_NUMBER TMP_QCS26652FB06
J 0
(-7050 1300);
DISPLAY 0.489362 (-7050 1300);
PAINT SKYBLUE (-7050 1300);
FORCEPROP 1 LAST PACK_TYPE 0402LF
J 0
(-7050 1275);
DISPLAY 0.489362 (-7050 1275);
PAINT SKYBLUE (-7050 1275);
FORCEPROP 2 LAST CDS_LIB pure_quanta
J 0
(-7100 1375);
DISPLAY INVISIBLE (-7100 1375);
FORCEPROP 1 LAST PATH I3
J 0
(-7050 1550);
DISPLAY 0.978723 (-7050 1550);
PAINT WHITE (-7050 1550);
DISPLAY INVISIBLE (-7050 1550);
FORCEADD Q_CAP..1
(-2750 1025);
FORCEPROP 1 LAST LOCATION PC253
J 0
(-2700 1125);
DISPLAY 0.489362 (-2700 1125);
PAINT SKYBLUE (-2700 1125);
FORCEPROP 0 LAST $SEC 1
J 0
(-2700 1150);
DISPLAY 0.680851 (-2700 1150);
PAINT MONO (-2700 1150);
DISPLAY INVISIBLE (-2700 1150);
FORCEPROP 0 LAST CDS_SEC 1
J 0
(-2700 1150);
DISPLAY 1.021277 (-2700 1150);
DISPLAY INVISIBLE (-2700 1150);
FORCEPROP 1 LASTPIN (-2750 1125) $PN 1
J 0
(-2740 1105);
DISPLAY 0.489362 (-2740 1105);
PAINT MONO (-2740 1105);
FORCEPROP 1 LASTPIN (-2750 925) $PN 2
J 0
(-2740 905);
DISPLAY 0.489362 (-2740 905);
PAINT MONO (-2740 905);
FORCEPROP 1 LAST MATERIAL X7R
J 0
(-2700 925);
DISPLAY 0.489362 (-2700 925);
PAINT SKYBLUE (-2700 925);
FORCEPROP 1 LAST TOLERANCE 10%
J 0
(-2700 975);
DISPLAY 0.489362 (-2700 975);
PAINT SKYBLUE (-2700 975);
FORCEPROP 1 LAST VALUE 470PF
J 0
(-2700 1075);
DISPLAY 0.489362 (-2700 1075);
PAINT SKYBLUE (-2700 1075);
FORCEPROP 1 LAST PART_NUMBER TMP_QCH14706KB18
J 0
(-2700 875);
DISPLAY 0.489362 (-2700 875);
PAINT SKYBLUE (-2700 875);
FORCEPROP 1 LAST VOLTAGE 50V
J 0
(-2700 1025);
DISPLAY 0.489362 (-2700 1025);
PAINT SKYBLUE (-2700 1025);
FORCEPROP 1 LAST PACK_TYPE 0402
J 0
(-2700 825);
DISPLAY 0.489362 (-2700 825);
PAINT SKYBLUE (-2700 825);
FORCEPROP 2 LAST CDS_LIB pure_quanta
J 0
(-2750 1025);
DISPLAY INVISIBLE (-2750 1025);
FORCEPROP 1 LAST PATH I35
J 0
(-2700 1175);
DISPLAY 0.978723 (-2700 1175);
PAINT WHITE (-2700 1175);
DISPLAY INVISIBLE (-2700 1175);
FORCEADD Q_CAP..1
(-3375 700);
FORCEPROP 1 LAST LOCATION PC250
J 0
(-3325 800);
DISPLAY 0.489362 (-3325 800);
PAINT SKYBLUE (-3325 800);
FORCEPROP 0 LAST $SEC 1
J 0
(-3325 825);
DISPLAY 0.680851 (-3325 825);
PAINT MONO (-3325 825);
DISPLAY INVISIBLE (-3325 825);
FORCEPROP 0 LAST CDS_SEC 1
J 0
(-3325 825);
DISPLAY 1.021277 (-3325 825);
DISPLAY INVISIBLE (-3325 825);
FORCEPROP 1 LASTPIN (-3375 800) $PN 1
J 0
(-3365 780);
DISPLAY 0.489362 (-3365 780);
PAINT MONO (-3365 780);
FORCEPROP 1 LASTPIN (-3375 600) $PN 2
J 0
(-3365 580);
DISPLAY 0.489362 (-3365 580);
PAINT MONO (-3365 580);
FORCEPROP 1 LAST MATERIAL X7R
J 0
(-3325 600);
DISPLAY 0.489362 (-3325 600);
PAINT SKYBLUE (-3325 600);
FORCEPROP 1 LAST TOLERANCE 10%
J 0
(-3325 650);
DISPLAY 0.489362 (-3325 650);
PAINT SKYBLUE (-3325 650);
FORCEPROP 1 LAST VALUE 470PF
J 0
(-3325 750);
DISPLAY 0.489362 (-3325 750);
PAINT SKYBLUE (-3325 750);
FORCEPROP 1 LAST PART_NUMBER TMP_QCH14706KB18
J 0
(-3325 550);
DISPLAY 0.489362 (-3325 550);
PAINT SKYBLUE (-3325 550);
FORCEPROP 1 LAST VOLTAGE 50V
J 0
(-3325 700);
DISPLAY 0.489362 (-3325 700);
PAINT SKYBLUE (-3325 700);
FORCEPROP 1 LAST PACK_TYPE 0402
J 0
(-3325 500);
DISPLAY 0.489362 (-3325 500);
PAINT SKYBLUE (-3325 500);
FORCEPROP 2 LAST CDS_LIB pure_quanta
J 0
(-3375 700);
DISPLAY INVISIBLE (-3375 700);
FORCEPROP 1 LAST PATH I36
J 0
(-3325 850);
DISPLAY 0.978723 (-3325 850);
PAINT WHITE (-3325 850);
DISPLAY INVISIBLE (-3325 850);
FORCEADD UNIVERSAL_GND..1
(-3375 425);
FORCEPROP 3 LASTPIN (-3375 475) SIG_NAME GND\g
J 0
(-3365 485);
DISPLAY 0.659574 (-3365 485);
PAINT MONO (-3365 485);
DISPLAY INVISIBLE (-3365 485);
FORCEPROP 2 LAST CDS_LIB pure_quanta_power
J 0
(-3375 425);
DISPLAY INVISIBLE (-3375 425);
FORCEPROP 1 LAST PATH I37
J 0
(-3300 425);
DISPLAY 0.872340 (-3300 425);
PAINT AQUA (-3300 425);
DISPLAY INVISIBLE (-3300 425);
FORCEPROP 1 LAST HDL_POWER GND
J 1
(-3350 350);
DISPLAY 0.872340 (-3350 350);
PAINT GREEN (-3350 350);
DISPLAY INVISIBLE (-3350 350);
FORCEADD UNIVERSAL_GND..1
(-2750 775);
FORCEPROP 3 LASTPIN (-2750 825) SIG_NAME GND\g
J 0
(-2740 835);
DISPLAY 0.659574 (-2740 835);
PAINT MONO (-2740 835);
DISPLAY INVISIBLE (-2740 835);
FORCEPROP 2 LAST CDS_LIB pure_quanta_power
J 0
(-2750 775);
DISPLAY INVISIBLE (-2750 775);
FORCEPROP 1 LAST PATH I38
J 0
(-2675 775);
DISPLAY 0.872340 (-2675 775);
PAINT AQUA (-2675 775);
DISPLAY INVISIBLE (-2675 775);
FORCEPROP 1 LAST HDL_POWER GND
J 1
(-2725 700);
DISPLAY 0.872340 (-2725 700);
PAINT GREEN (-2725 700);
DISPLAY INVISIBLE (-2725 700);
FORCEADD Q_RES..2
(-7775 2075);
FORCEPROP 1 LAST LOCATION PR152
J 0
(-7725 2125);
DISPLAY 0.489362 (-7725 2125);
PAINT SKYBLUE (-7725 2125);
FORCEPROP 0 LAST $SEC 1
J 0
(-7750 2150);
DISPLAY 0.680851 (-7750 2150);
PAINT MONO (-7750 2150);
DISPLAY INVISIBLE (-7750 2150);
FORCEPROP 0 LAST CDS_SEC 1
J 0
(-7750 2150);
DISPLAY 1.021277 (-7750 2150);
DISPLAY INVISIBLE (-7750 2150);
FORCEPROP 1 LASTPIN (-7775 2175) $PN 1
J 0
(-7770 2137);
DISPLAY 0.489362 (-7770 2137);
PAINT MONO (-7770 2137);
FORCEPROP 1 LASTPIN (-7775 1975) $PN 2
J 0
(-7770 1985);
DISPLAY 0.489362 (-7770 1985);
PAINT MONO (-7770 1985);
FORCEPROP 1 LAST WATTAGE 1/16W
J 0
(-7725 2050);
DISPLAY 0.489362 (-7725 2050);
PAINT SKYBLUE (-7725 2050);
FORCEPROP 1 LAST MATERIAL CHIP
J 0
(-7725 2025);
DISPLAY 0.489362 (-7725 2025);
PAINT SKYBLUE (-7725 2025);
FORCEPROP 1 LAST TOLERANCE 1%
J 0
(-7725 2075);
DISPLAY 0.489362 (-7725 2075);
PAINT SKYBLUE (-7725 2075);
FORCEPROP 1 LAST VALUE 1K
J 0
(-7725 2100);
DISPLAY 0.489362 (-7725 2100);
PAINT SKYBLUE (-7725 2100);
FORCEPROP 1 LAST PART_NUMBER TMP_QCS21002FB24
J 0
(-7725 2000);
DISPLAY 0.489362 (-7725 2000);
PAINT SKYBLUE (-7725 2000);
FORCEPROP 1 LAST PACK_TYPE 0402LF
J 0
(-7725 1975);
DISPLAY 0.489362 (-7725 1975);
PAINT SKYBLUE (-7725 1975);
FORCEPROP 2 LAST CDS_LIB pure_quanta
J 0
(-7775 2075);
DISPLAY INVISIBLE (-7775 2075);
FORCEPROP 1 LAST PATH I4
J 0
(-7725 2250);
DISPLAY 0.978723 (-7725 2250);
PAINT WHITE (-7725 2250);
DISPLAY INVISIBLE (-7725 2250);
FORCEADD Q_CAP..2
(-5250 6375);
FORCEPROP 1 LAST LOCATION PC248
J 1
(-5250 6450);
DISPLAY 0.489362 (-5250 6450);
PAINT SKYBLUE (-5250 6450);
FORCEPROP 0 LAST $SEC 1
J 0
(-5250 6475);
DISPLAY 0.680851 (-5250 6475);
PAINT MONO (-5250 6475);
DISPLAY INVISIBLE (-5250 6475);
FORCEPROP 0 LAST CDS_SEC 1
J 0
(-5250 6475);
DISPLAY 1.021277 (-5250 6475);
DISPLAY INVISIBLE (-5250 6475);
FORCEPROP 1 LASTPIN (-5350 6375) $PN 1
J 0
(-5360 6390);
DISPLAY 0.489362 (-5360 6390);
PAINT MONO (-5360 6390);
FORCEPROP 1 LASTPIN (-5150 6375) $PN 2
J 0
(-5165 6390);
DISPLAY 0.489362 (-5165 6390);
PAINT MONO (-5165 6390);
FORCEPROP 1 LAST MATERIAL EMPTY
J 0
(-5525 6250);
DISPLAY 0.489362 (-5525 6250);
PAINT RED (-5525 6250);
FORCEPROP 1 LAST TOLERANCE 5%
J 0
(-5125 6250);
DISPLAY 0.489362 (-5125 6250);
PAINT SKYBLUE (-5125 6250);
FORCEPROP 1 LAST VALUE 1000PF
J 2
(-5375 6425);
DISPLAY 0.489362 (-5375 6425);
PAINT SKYBLUE (-5375 6425);
FORCEPROP 1 LAST PART_NUMBER TMP_QCH21006JB10
J 1
(-5400 6300);
DISPLAY 0.489362 (-5400 6300);
PAINT SKYBLUE (-5400 6300);
FORCEPROP 1 LAST VOLTAGE 50V
J 0
(-5150 6425);
DISPLAY 0.489362 (-5150 6425);
PAINT SKYBLUE (-5150 6425);
FORCEPROP 1 LAST PACK_TYPE 0402
J 0
(-5125 6300);
DISPLAY 0.489362 (-5125 6300);
PAINT SKYBLUE (-5125 6300);
FORCEPROP 2 LAST CDS_LIB pure_quanta
J 0
(-5250 6375);
DISPLAY INVISIBLE (-5250 6375);
FORCEPROP 1 LAST PATH I42
J 0
(-5250 6575);
DISPLAY 0.978723 (-5250 6575);
PAINT WHITE (-5250 6575);
DISPLAY INVISIBLE (-5250 6575);
FORCEADD Q_RES..1
(-5900 6100);
FORCEPROP 1 LAST LOCATION PR178
J 0
(-5950 6150);
DISPLAY 0.489362 (-5950 6150);
PAINT SKYBLUE (-5950 6150);
FORCEPROP 0 LAST $SEC 1
J 0
(-5775 6150);
DISPLAY 0.680851 (-5775 6150);
PAINT MONO (-5775 6150);
DISPLAY INVISIBLE (-5775 6150);
FORCEPROP 0 LAST CDS_SEC 1
J 0
(-5775 6150);
DISPLAY 1.021277 (-5775 6150);
DISPLAY INVISIBLE (-5775 6150);
FORCEPROP 1 LASTPIN (-6000 6100) $PN 1
J 0
(-5988 6112);
DISPLAY 0.489362 (-5988 6112);
PAINT MONO (-5988 6112);
FORCEPROP 1 LASTPIN (-5800 6100) $PN 2
J 0
(-5838 6112);
DISPLAY 0.489362 (-5838 6112);
PAINT MONO (-5838 6112);
FORCEPROP 1 LAST WATTAGE 1/16W
J 0
(-5800 6050);
DISPLAY 0.489362 (-5800 6050);
PAINT SKYBLUE (-5800 6050);
FORCEPROP 1 LAST MATERIAL CHIP
J 0
(-6150 6025);
DISPLAY 0.489362 (-6150 6025);
PAINT SKYBLUE (-6150 6025);
FORCEPROP 1 LAST TOLERANCE 5%
J 0
(-5775 6125);
DISPLAY 0.489362 (-5775 6125);
PAINT SKYBLUE (-5775 6125);
FORCEPROP 1 LAST VALUE 0
J 2
(-6025 6125);
DISPLAY 0.489362 (-6025 6125);
PAINT SKYBLUE (-6025 6125);
FORCEPROP 1 LAST PART_NUMBER CS00002JB38
J 0
(-6150 6050);
DISPLAY 0.489362 (-6150 6050);
PAINT SKYBLUE (-6150 6050);
FORCEPROP 1 LAST PACK_TYPE 0402LF
J 0
(-5800 6025);
DISPLAY 0.489362 (-5800 6025);
PAINT SKYBLUE (-5800 6025);
FORCEPROP 2 LAST CDS_LIB pure_quanta
J 0
(-5900 6100);
DISPLAY INVISIBLE (-5900 6100);
FORCEPROP 1 LAST PATH I43
J 0
(-5950 6250);
DISPLAY 0.978723 (-5950 6250);
PAINT WHITE (-5950 6250);
DISPLAY INVISIBLE (-5950 6250);
FORCEADD UNIVERSAL_GND..1
(-5000 6300);
FORCEPROP 3 LASTPIN (-5000 6350) SIG_NAME GND\g
J 0
(-4990 6360);
DISPLAY 0.659574 (-4990 6360);
PAINT MONO (-4990 6360);
DISPLAY INVISIBLE (-4990 6360);
FORCEPROP 2 LAST CDS_LIB pure_quanta_power
J 0
(-5000 6300);
DISPLAY INVISIBLE (-5000 6300);
FORCEPROP 1 LAST PATH I44
J 0
(-4925 6300);
DISPLAY 0.872340 (-4925 6300);
PAINT AQUA (-4925 6300);
DISPLAY INVISIBLE (-4925 6300);
FORCEPROP 1 LAST HDL_POWER GND
J 1
(-4975 6225);
DISPLAY 0.872340 (-4975 6225);
PAINT GREEN (-4975 6225);
DISPLAY INVISIBLE (-4975 6225);
FORCEADD OFFPAGE..2
R 2
(-6625 6100);
FORCEPROP 2 LAST $XR0 80 
J 0
(-6879 6100);
DISPLAY 0.638298 (-6879 6100);
PAINT MONO (-6879 6100);
FORCEPROP 2 LAST CDS_LIB standard
J 2
(-6625 6100);
DISPLAY INVISIBLE (-6625 6100);
FORCEPROP 1 LAST OFFPAGE TRUE
J 2
(-6950 5975);
DISPLAY 0.872340 (-6950 5975);
PAINT GREEN (-6950 5975);
DISPLAY INVISIBLE (-6950 5975);
FORCEPROP 1 LAST COMMENT_BODY TRUE
J 2
(-6580 6005);
DISPLAY 0.872340 (-6580 6005);
PAINT GREEN (-6580 6005);
DISPLAY INVISIBLE (-6580 6005);
FORCEPROP 2 LAST PATH I45
J 2
(-6800 6175);
DISPLAY 1.021277 (-6800 6175);
DISPLAY INVISIBLE (-6800 6175);
FORCEADD VCC_CORE..1
(-6525 6500);
FORCEPROP 3 LASTPIN (-6525 6450) SIG_NAME P3V3_STBY\g
J 0
(-6515 6460);
DISPLAY 0.659574 (-6515 6460);
PAINT MONO (-6515 6460);
DISPLAY INVISIBLE (-6515 6460);
FORCEPROP 1 LAST HDL_POWER P3V3_STBY
J 1
(-6525 6550);
DISPLAY 0.489362 (-6525 6550);
PAINT GREEN (-6525 6550);
FORCEPROP 2 LAST CDS_LIB pure_quanta_power
J 0
(-6525 6500);
DISPLAY INVISIBLE (-6525 6500);
FORCEPROP 1 LAST PATH I46
J 0
(-6475 6525);
DISPLAY 0.872340 (-6475 6525);
PAINT AQUA (-6475 6525);
DISPLAY INVISIBLE (-6475 6525);
FORCEADD Q_RES..1
(-5900 5950);
FORCEPROP 1 LAST LOCATION PR179
J 0
(-5950 5975);
DISPLAY 0.489362 (-5950 5975);
PAINT SKYBLUE (-5950 5975);
FORCEPROP 0 LAST $SEC 1
J 0
(-5775 6000);
DISPLAY 0.680851 (-5775 6000);
PAINT MONO (-5775 6000);
DISPLAY INVISIBLE (-5775 6000);
FORCEPROP 0 LAST CDS_SEC 1
J 0
(-5775 6000);
DISPLAY 1.021277 (-5775 6000);
DISPLAY INVISIBLE (-5775 6000);
FORCEPROP 1 LASTPIN (-6000 5950) $PN 1
J 0
(-5988 5962);
DISPLAY 0.489362 (-5988 5962);
PAINT MONO (-5988 5962);
FORCEPROP 1 LASTPIN (-5800 5950) $PN 2
J 0
(-5838 5962);
DISPLAY 0.489362 (-5838 5962);
PAINT MONO (-5838 5962);
FORCEPROP 1 LAST WATTAGE 1/16W
J 0
(-5800 5900);
DISPLAY 0.489362 (-5800 5900);
PAINT SKYBLUE (-5800 5900);
FORCEPROP 1 LAST MATERIAL CHIP
J 0
(-6150 5875);
DISPLAY 0.489362 (-6150 5875);
PAINT SKYBLUE (-6150 5875);
FORCEPROP 1 LAST TOLERANCE 5%
J 0
(-5775 5975);
DISPLAY 0.489362 (-5775 5975);
PAINT SKYBLUE (-5775 5975);
FORCEPROP 1 LAST VALUE 0
J 2
(-6025 5975);
DISPLAY 0.489362 (-6025 5975);
PAINT SKYBLUE (-6025 5975);
FORCEPROP 1 LAST PART_NUMBER CS00002JB38
J 0
(-6150 5900);
DISPLAY 0.489362 (-6150 5900);
PAINT SKYBLUE (-6150 5900);
FORCEPROP 1 LAST PACK_TYPE 0402LF
J 0
(-5800 5875);
DISPLAY 0.489362 (-5800 5875);
PAINT SKYBLUE (-5800 5875);
FORCEPROP 2 LAST CDS_LIB pure_quanta
J 0
(-5900 5950);
DISPLAY INVISIBLE (-5900 5950);
FORCEPROP 1 LAST PATH I47
J 0
(-5950 6100);
DISPLAY 0.978723 (-5950 6100);
PAINT WHITE (-5950 6100);
DISPLAY INVISIBLE (-5950 6100);
FORCEADD Q_CAP..2
(-5225 5825);
FORCEPROP 1 LAST LOCATION PC249
J 1
(-5225 5875);
DISPLAY 0.489362 (-5225 5875);
PAINT SKYBLUE (-5225 5875);
FORCEPROP 0 LAST $SEC 1
J 0
(-5225 5925);
DISPLAY 0.680851 (-5225 5925);
PAINT MONO (-5225 5925);
DISPLAY INVISIBLE (-5225 5925);
FORCEPROP 0 LAST CDS_SEC 1
J 0
(-5225 5925);
DISPLAY 1.021277 (-5225 5925);
DISPLAY INVISIBLE (-5225 5925);
FORCEPROP 1 LASTPIN (-5325 5825) $PN 1
J 0
(-5335 5840);
DISPLAY 0.489362 (-5335 5840);
PAINT MONO (-5335 5840);
FORCEPROP 1 LASTPIN (-5125 5825) $PN 2
J 0
(-5140 5840);
DISPLAY 0.489362 (-5140 5840);
PAINT MONO (-5140 5840);
FORCEPROP 1 LAST TOLERANCE 5%
J 0
(-5125 5775);
DISPLAY 0.489362 (-5125 5775);
PAINT SKYBLUE (-5125 5775);
FORCEPROP 1 LAST VOLTAGE 50V
J 0
(-5075 5850);
DISPLAY 0.489362 (-5075 5850);
PAINT SKYBLUE (-5075 5850);
FORCEPROP 1 LAST MATERIAL X7R
J 0
(-5650 5775);
DISPLAY 0.489362 (-5650 5775);
PAINT SKYBLUE (-5650 5775);
FORCEPROP 1 LAST VALUE 1000PF
J 2
(-5400 5850);
DISPLAY 0.489362 (-5400 5850);
PAINT SKYBLUE (-5400 5850);
FORCEPROP 1 LAST PART_NUMBER TMP_QCH21006JB10
J 0
(-5650 5800);
DISPLAY 0.489362 (-5650 5800);
PAINT SKYBLUE (-5650 5800);
FORCEPROP 1 LAST PACK_TYPE 0402
J 0
(-5125 5800);
DISPLAY 0.489362 (-5125 5800);
PAINT SKYBLUE (-5125 5800);
FORCEPROP 2 LAST CDS_LIB pure_quanta
J 0
(-5225 5825);
DISPLAY INVISIBLE (-5225 5825);
FORCEPROP 1 LAST PATH I49
J 0
(-5225 6025);
DISPLAY 0.978723 (-5225 6025);
PAINT WHITE (-5225 6025);
DISPLAY INVISIBLE (-5225 6025);
FORCEADD UNIVERSAL_GND..1
(-7100 1175);
FORCEPROP 3 LASTPIN (-7100 1225) SIG_NAME GND\g
J 0
(-7090 1235);
DISPLAY 0.659574 (-7090 1235);
PAINT MONO (-7090 1235);
DISPLAY INVISIBLE (-7090 1235);
FORCEPROP 2 LAST CDS_LIB pure_quanta_power
J 0
(-7100 1175);
DISPLAY INVISIBLE (-7100 1175);
FORCEPROP 1 LAST PATH I5
J 0
(-7025 1175);
DISPLAY 0.872340 (-7025 1175);
PAINT AQUA (-7025 1175);
DISPLAY INVISIBLE (-7025 1175);
FORCEPROP 1 LAST HDL_POWER GND
J 1
(-7075 1100);
DISPLAY 0.872340 (-7075 1100);
PAINT GREEN (-7075 1100);
DISPLAY INVISIBLE (-7075 1100);
FORCEADD UNIVERSAL_GND..1
(-5000 5750);
FORCEPROP 3 LASTPIN (-5000 5800) SIG_NAME GND\g
J 0
(-4990 5810);
DISPLAY 0.659574 (-4990 5810);
PAINT MONO (-4990 5810);
DISPLAY INVISIBLE (-4990 5810);
FORCEPROP 2 LAST CDS_LIB pure_quanta_power
J 0
(-5000 5750);
DISPLAY INVISIBLE (-5000 5750);
FORCEPROP 1 LAST PATH I50
J 0
(-4925 5750);
DISPLAY 0.872340 (-4925 5750);
PAINT AQUA (-4925 5750);
DISPLAY INVISIBLE (-4925 5750);
FORCEPROP 1 LAST HDL_POWER GND
J 1
(-4975 5675);
DISPLAY 0.872340 (-4975 5675);
PAINT GREEN (-4975 5675);
DISPLAY INVISIBLE (-4975 5675);
FORCEADD OFFPAGE..2
R 2
(-8900 5350);
FORCEPROP 2 LAST $XR0 54 
J 0
(-9124 5350);
DISPLAY 0.638298 (-9124 5350);
PAINT MONO (-9124 5350);
FORCEPROP 2 LAST CDS_LIB standard
J 0
(-8900 5350);
DISPLAY INVISIBLE (-8900 5350);
FORCEPROP 1 LAST OFFPAGE TRUE
J 2
(-9225 5225);
DISPLAY 0.872340 (-9225 5225);
PAINT GREEN (-9225 5225);
DISPLAY INVISIBLE (-9225 5225);
FORCEPROP 1 LAST COMMENT_BODY TRUE
J 2
(-8855 5255);
DISPLAY 0.872340 (-8855 5255);
PAINT GREEN (-8855 5255);
DISPLAY INVISIBLE (-8855 5255);
FORCEPROP 2 LAST PATH I53
J 0
(-8850 5425);
DISPLAY 1.021277 (-8850 5425);
DISPLAY INVISIBLE (-8850 5425);
FORCEADD Q_RES..2
(-8000 5975);
FORCEPROP 1 LAST LOCATION PR154
J 0
(-7950 6100);
DISPLAY 0.489362 (-7950 6100);
PAINT SKYBLUE (-7950 6100);
FORCEPROP 0 LAST $SEC 1
J 0
(-7950 6125);
DISPLAY 0.680851 (-7950 6125);
PAINT MONO (-7950 6125);
DISPLAY INVISIBLE (-7950 6125);
FORCEPROP 0 LAST CDS_SEC 1
J 0
(-7950 6125);
DISPLAY 1.021277 (-7950 6125);
DISPLAY INVISIBLE (-7950 6125);
FORCEPROP 1 LASTPIN (-8000 6075) $PN 1
J 0
(-7995 6037);
DISPLAY 0.489362 (-7995 6037);
PAINT MONO (-7995 6037);
FORCEPROP 1 LASTPIN (-8000 5875) $PN 2
J 0
(-7995 5885);
DISPLAY 0.489362 (-7995 5885);
PAINT MONO (-7995 5885);
FORCEPROP 1 LAST WATTAGE 1/16W
J 0
(-7950 5950);
DISPLAY 0.489362 (-7950 5950);
PAINT SKYBLUE (-7950 5950);
FORCEPROP 1 LAST MATERIAL EMPTY
J 0
(-7950 5900);
DISPLAY 0.489362 (-7950 5900);
PAINT RED (-7950 5900);
FORCEPROP 1 LAST TOLERANCE 1%
J 0
(-7950 6000);
DISPLAY 0.489362 (-7950 6000);
PAINT SKYBLUE (-7950 6000);
FORCEPROP 1 LAST VALUE 1K
J 0
(-7950 6050);
DISPLAY 0.489362 (-7950 6050);
PAINT SKYBLUE (-7950 6050);
FORCEPROP 1 LAST PACK_TYPE 0402LF
J 0
(-7950 5850);
DISPLAY 0.489362 (-7950 5850);
PAINT SKYBLUE (-7950 5850);
FORCEPROP 2 LAST CDS_LIB pure_quanta
J 0
(-8000 5975);
DISPLAY INVISIBLE (-8000 5975);
FORCEPROP 1 LAST PATH I55
J 0
(-7950 6150);
DISPLAY 0.978723 (-7950 6150);
PAINT WHITE (-7950 6150);
DISPLAY INVISIBLE (-7950 6150);
FORCEPROP 1 LAST PART_NUMBER TMP_QCS21002FB24
J 0
(-7960 5850);
DISPLAY 0.489362 (-7960 5850);
PAINT SKYBLUE (-7960 5850);
DISPLAY INVISIBLE (-7960 5850);
FORCEADD Q_RES..2
(-8350 5975);
FORCEPROP 1 LAST LOCATION PR151
J 0
(-8300 6100);
DISPLAY 0.489362 (-8300 6100);
PAINT SKYBLUE (-8300 6100);
FORCEPROP 0 LAST $SEC 1
J 0
(-8300 6125);
DISPLAY 0.680851 (-8300 6125);
PAINT MONO (-8300 6125);
DISPLAY INVISIBLE (-8300 6125);
FORCEPROP 0 LAST CDS_SEC 1
J 0
(-8300 6125);
DISPLAY 1.021277 (-8300 6125);
DISPLAY INVISIBLE (-8300 6125);
FORCEPROP 1 LASTPIN (-8350 6075) $PN 1
J 0
(-8345 6037);
DISPLAY 0.489362 (-8345 6037);
PAINT MONO (-8345 6037);
FORCEPROP 1 LASTPIN (-8350 5875) $PN 2
J 0
(-8345 5885);
DISPLAY 0.489362 (-8345 5885);
PAINT MONO (-8345 5885);
FORCEPROP 1 LAST WATTAGE 1/16W
J 0
(-8300 5950);
DISPLAY 0.489362 (-8300 5950);
PAINT SKYBLUE (-8300 5950);
FORCEPROP 1 LAST MATERIAL EMPTY
J 0
(-8300 5900);
DISPLAY 0.489362 (-8300 5900);
PAINT RED (-8300 5900);
FORCEPROP 1 LAST TOLERANCE 1%
J 0
(-8300 6000);
DISPLAY 0.489362 (-8300 6000);
PAINT SKYBLUE (-8300 6000);
FORCEPROP 1 LAST VALUE 1K
J 0
(-8300 6050);
DISPLAY 0.489362 (-8300 6050);
PAINT SKYBLUE (-8300 6050);
FORCEPROP 1 LAST PACK_TYPE 0402LF
J 0
(-8300 5850);
DISPLAY 0.489362 (-8300 5850);
PAINT SKYBLUE (-8300 5850);
FORCEPROP 2 LAST CDS_LIB pure_quanta
J 0
(-8350 5975);
DISPLAY INVISIBLE (-8350 5975);
FORCEPROP 1 LAST PATH I56
J 0
(-8300 6150);
DISPLAY 0.978723 (-8300 6150);
PAINT WHITE (-8300 6150);
DISPLAY INVISIBLE (-8300 6150);
FORCEPROP 1 LAST PART_NUMBER TMP_QCS21002FB24
J 0
(-8300 5850);
DISPLAY 0.489362 (-8300 5850);
PAINT SKYBLUE (-8300 5850);
DISPLAY INVISIBLE (-8300 5850);
FORCEADD Q_RES..2
(-7700 5975);
FORCEPROP 1 LAST LOCATION PR156
J 0
(-7650 6100);
DISPLAY 0.489362 (-7650 6100);
PAINT SKYBLUE (-7650 6100);
FORCEPROP 0 LAST $SEC 1
J 0
(-7650 6125);
DISPLAY 0.680851 (-7650 6125);
PAINT MONO (-7650 6125);
DISPLAY INVISIBLE (-7650 6125);
FORCEPROP 0 LAST CDS_SEC 1
J 0
(-7650 6125);
DISPLAY 1.021277 (-7650 6125);
DISPLAY INVISIBLE (-7650 6125);
FORCEPROP 1 LASTPIN (-7700 6075) $PN 1
J 0
(-7695 6037);
DISPLAY 0.489362 (-7695 6037);
PAINT MONO (-7695 6037);
FORCEPROP 1 LASTPIN (-7700 5875) $PN 2
J 0
(-7695 5885);
DISPLAY 0.489362 (-7695 5885);
PAINT MONO (-7695 5885);
FORCEPROP 1 LAST WATTAGE 1/16W
J 0
(-7650 5950);
DISPLAY 0.489362 (-7650 5950);
PAINT SKYBLUE (-7650 5950);
FORCEPROP 1 LAST MATERIAL EMPTY
J 0
(-7650 5900);
DISPLAY 0.489362 (-7650 5900);
PAINT RED (-7650 5900);
FORCEPROP 1 LAST TOLERANCE 1%
J 0
(-7650 6000);
DISPLAY 0.489362 (-7650 6000);
PAINT SKYBLUE (-7650 6000);
FORCEPROP 1 LAST VALUE 1K
J 0
(-7650 6050);
DISPLAY 0.489362 (-7650 6050);
PAINT SKYBLUE (-7650 6050);
FORCEPROP 1 LAST PACK_TYPE 0402LF
J 0
(-7650 5850);
DISPLAY 0.489362 (-7650 5850);
PAINT SKYBLUE (-7650 5850);
FORCEPROP 2 LAST CDS_LIB pure_quanta
J 0
(-7700 5975);
DISPLAY INVISIBLE (-7700 5975);
FORCEPROP 1 LAST PATH I57
J 0
(-7650 6150);
DISPLAY 0.978723 (-7650 6150);
PAINT WHITE (-7650 6150);
DISPLAY INVISIBLE (-7650 6150);
FORCEPROP 1 LAST PART_NUMBER TMP_QCS21002FB24
J 0
(-7660 5850);
DISPLAY 0.489362 (-7660 5850);
PAINT SKYBLUE (-7660 5850);
DISPLAY INVISIBLE (-7660 5850);
FORCEADD Q_RES..2
(-7425 5975);
FORCEPROP 1 LAST LOCATION PR160
J 0
(-7375 6100);
DISPLAY 0.489362 (-7375 6100);
PAINT SKYBLUE (-7375 6100);
FORCEPROP 0 LAST $SEC 1
J 0
(-7375 6125);
DISPLAY 0.680851 (-7375 6125);
PAINT MONO (-7375 6125);
DISPLAY INVISIBLE (-7375 6125);
FORCEPROP 0 LAST CDS_SEC 1
J 0
(-7375 6125);
DISPLAY 1.021277 (-7375 6125);
DISPLAY INVISIBLE (-7375 6125);
FORCEPROP 1 LASTPIN (-7425 6075) $PN 1
J 0
(-7420 6037);
DISPLAY 0.489362 (-7420 6037);
PAINT MONO (-7420 6037);
FORCEPROP 1 LASTPIN (-7425 5875) $PN 2
J 0
(-7420 5885);
DISPLAY 0.489362 (-7420 5885);
PAINT MONO (-7420 5885);
FORCEPROP 1 LAST WATTAGE 1/16W
J 0
(-7375 5950);
DISPLAY 0.489362 (-7375 5950);
PAINT SKYBLUE (-7375 5950);
FORCEPROP 1 LAST MATERIAL EMPTY
J 0
(-7375 5900);
DISPLAY 0.489362 (-7375 5900);
PAINT RED (-7375 5900);
FORCEPROP 1 LAST TOLERANCE 1%
J 0
(-7375 6000);
DISPLAY 0.489362 (-7375 6000);
PAINT SKYBLUE (-7375 6000);
FORCEPROP 1 LAST VALUE 1K
J 0
(-7375 6050);
DISPLAY 0.489362 (-7375 6050);
PAINT SKYBLUE (-7375 6050);
FORCEPROP 1 LAST PART_NUMBER TMP_QCS21002FB24
J 0
(-7375 5850);
DISPLAY 0.489362 (-7375 5850);
PAINT SKYBLUE (-7375 5850);
FORCEPROP 1 LAST PACK_TYPE 0402LF
J 0
(-7375 5800);
DISPLAY 0.489362 (-7375 5800);
PAINT SKYBLUE (-7375 5800);
FORCEPROP 2 LAST CDS_LIB pure_quanta
J 0
(-7425 5975);
DISPLAY INVISIBLE (-7425 5975);
FORCEPROP 1 LAST PATH I58
J 0
(-7375 6150);
DISPLAY 0.978723 (-7375 6150);
PAINT WHITE (-7375 6150);
DISPLAY INVISIBLE (-7375 6150);
FORCEADD VCC_CORE..1
(-8350 6275);
FORCEPROP 3 LASTPIN (-8350 6225) SIG_NAME PVDD18_S5_P1\g
J 0
(-8340 6235);
DISPLAY 0.659574 (-8340 6235);
PAINT MONO (-8340 6235);
DISPLAY INVISIBLE (-8340 6235);
FORCEPROP 1 LAST HDL_POWER PVDD18_S5_P1
J 1
(-8350 6325);
DISPLAY 0.489362 (-8350 6325);
PAINT GREEN (-8350 6325);
FORCEPROP 2 LAST CDS_LIB pure_quanta_power
J 0
(-8350 6275);
DISPLAY INVISIBLE (-8350 6275);
FORCEPROP 1 LAST PATH I59
J 0
(-8300 6300);
DISPLAY 0.872340 (-8300 6300);
PAINT AQUA (-8300 6300);
DISPLAY INVISIBLE (-8300 6300);
FORCEADD VCC_CORE..1
(-7775 2300);
FORCEPROP 3 LASTPIN (-7775 2250) SIG_NAME P3V3_STBY\g
J 0
(-7765 2260);
DISPLAY 0.659574 (-7765 2260);
PAINT MONO (-7765 2260);
DISPLAY INVISIBLE (-7765 2260);
FORCEPROP 1 LAST HDL_POWER P3V3_STBY
J 1
(-7775 2350);
DISPLAY 0.489362 (-7775 2350);
PAINT GREEN (-7775 2350);
FORCEPROP 2 LAST CDS_LIB pure_quanta_power
J 0
(-7775 2300);
DISPLAY INVISIBLE (-7775 2300);
FORCEPROP 1 LAST PATH I6
J 0
(-7725 2325);
DISPLAY 0.872340 (-7725 2325);
PAINT AQUA (-7725 2325);
DISPLAY INVISIBLE (-7725 2325);
FORCEADD Q_RES..2
(-8250 5025);
FORCEPROP 1 LAST LOCATION PR153
J 0
(-8200 5150);
DISPLAY 0.489362 (-8200 5150);
PAINT SKYBLUE (-8200 5150);
FORCEPROP 0 LAST $SEC 1
J 0
(-8200 5175);
DISPLAY 0.680851 (-8200 5175);
PAINT MONO (-8200 5175);
DISPLAY INVISIBLE (-8200 5175);
FORCEPROP 0 LAST CDS_SEC 1
J 0
(-8200 5175);
DISPLAY 1.021277 (-8200 5175);
DISPLAY INVISIBLE (-8200 5175);
FORCEPROP 1 LASTPIN (-8250 5125) $PN 1
J 0
(-8245 5087);
DISPLAY 0.489362 (-8245 5087);
PAINT MONO (-8245 5087);
FORCEPROP 1 LASTPIN (-8250 4925) $PN 2
J 0
(-8245 4935);
DISPLAY 0.489362 (-8245 4935);
PAINT MONO (-8245 4935);
FORCEPROP 1 LAST WATTAGE 1/16W
J 0
(-8200 5000);
DISPLAY 0.489362 (-8200 5000);
PAINT SKYBLUE (-8200 5000);
FORCEPROP 1 LAST MATERIAL EMPTY
J 0
(-8200 4950);
DISPLAY 0.489362 (-8200 4950);
PAINT RED (-8200 4950);
FORCEPROP 1 LAST TOLERANCE 1%
J 0
(-8200 5050);
DISPLAY 0.489362 (-8200 5050);
PAINT SKYBLUE (-8200 5050);
FORCEPROP 1 LAST VALUE 1K
J 0
(-8200 5100);
DISPLAY 0.489362 (-8200 5100);
PAINT SKYBLUE (-8200 5100);
FORCEPROP 1 LAST PACK_TYPE 0402LF
J 0
(-8200 4900);
DISPLAY 0.489362 (-8200 4900);
PAINT SKYBLUE (-8200 4900);
FORCEPROP 2 LAST CDS_LIB pure_quanta
J 0
(-8250 5025);
DISPLAY INVISIBLE (-8250 5025);
FORCEPROP 1 LAST PATH I62
J 0
(-8200 5200);
DISPLAY 0.978723 (-8200 5200);
PAINT WHITE (-8200 5200);
DISPLAY INVISIBLE (-8200 5200);
FORCEPROP 1 LAST PART_NUMBER TMP_QCS21002FB24
J 0
(-8210 4900);
DISPLAY 0.489362 (-8210 4900);
PAINT SKYBLUE (-8210 4900);
DISPLAY INVISIBLE (-8210 4900);
FORCEADD UNIVERSAL_GND..1
(-8525 4775);
FORCEPROP 3 LASTPIN (-8525 4825) SIG_NAME GND\g
J 0
(-8515 4835);
DISPLAY 0.659574 (-8515 4835);
PAINT MONO (-8515 4835);
DISPLAY INVISIBLE (-8515 4835);
FORCEPROP 2 LAST CDS_LIB pure_quanta_power
J 0
(-8525 4775);
DISPLAY INVISIBLE (-8525 4775);
FORCEPROP 1 LAST PATH I64
J 0
(-8450 4775);
DISPLAY 0.872340 (-8450 4775);
PAINT AQUA (-8450 4775);
DISPLAY INVISIBLE (-8450 4775);
FORCEPROP 1 LAST HDL_POWER GND
J 1
(-8500 4700);
DISPLAY 0.872340 (-8500 4700);
PAINT GREEN (-8500 4700);
DISPLAY INVISIBLE (-8500 4700);
FORCEADD UNIVERSAL_GND..1
(-8250 4775);
FORCEPROP 3 LASTPIN (-8250 4825) SIG_NAME GND\g
J 0
(-8240 4835);
DISPLAY 0.659574 (-8240 4835);
PAINT MONO (-8240 4835);
DISPLAY INVISIBLE (-8240 4835);
FORCEPROP 2 LAST CDS_LIB pure_quanta_power
J 0
(-8250 4775);
DISPLAY INVISIBLE (-8250 4775);
FORCEPROP 1 LAST PATH I65
J 0
(-8175 4775);
DISPLAY 0.872340 (-8175 4775);
PAINT AQUA (-8175 4775);
DISPLAY INVISIBLE (-8175 4775);
FORCEPROP 1 LAST HDL_POWER GND
J 1
(-8225 4700);
DISPLAY 0.872340 (-8225 4700);
PAINT GREEN (-8225 4700);
DISPLAY INVISIBLE (-8225 4700);
FORCEADD Q_RES..1
(-5925 4800);
FORCEPROP 1 LAST LOCATION PR176
J 0
(-5975 4850);
DISPLAY 0.489362 (-5975 4850);
PAINT SKYBLUE (-5975 4850);
FORCEPROP 0 LAST $SEC 1
J 0
(-5975 4875);
DISPLAY 0.680851 (-5975 4875);
PAINT MONO (-5975 4875);
DISPLAY INVISIBLE (-5975 4875);
FORCEPROP 0 LAST CDS_SEC 1
J 0
(-5975 4875);
DISPLAY 1.021277 (-5975 4875);
DISPLAY INVISIBLE (-5975 4875);
FORCEPROP 1 LASTPIN (-6025 4800) $PN 1
J 0
(-6013 4812);
DISPLAY 0.489362 (-6013 4812);
PAINT MONO (-6013 4812);
FORCEPROP 1 LASTPIN (-5825 4800) $PN 2
J 0
(-5863 4812);
DISPLAY 0.489362 (-5863 4812);
PAINT MONO (-5863 4812);
FORCEPROP 1 LAST WATTAGE 1/16W
J 0
(-5825 4750);
DISPLAY 0.489362 (-5825 4750);
PAINT SKYBLUE (-5825 4750);
FORCEPROP 1 LAST MATERIAL CHIP
J 0
(-6175 4725);
DISPLAY 0.489362 (-6175 4725);
PAINT SKYBLUE (-6175 4725);
FORCEPROP 1 LAST TOLERANCE 5%
J 0
(-5800 4825);
DISPLAY 0.489362 (-5800 4825);
PAINT SKYBLUE (-5800 4825);
FORCEPROP 1 LAST VALUE 0
J 2
(-6050 4825);
DISPLAY 0.489362 (-6050 4825);
PAINT SKYBLUE (-6050 4825);
FORCEPROP 1 LAST PART_NUMBER CS00002JB38
J 0
(-6175 4750);
DISPLAY 0.489362 (-6175 4750);
PAINT SKYBLUE (-6175 4750);
FORCEPROP 1 LAST PACK_TYPE 0402LF
J 0
(-5825 4725);
DISPLAY 0.489362 (-5825 4725);
PAINT SKYBLUE (-5825 4725);
FORCEPROP 2 LAST CDS_LIB pure_quanta
J 0
(-5925 4800);
DISPLAY INVISIBLE (-5925 4800);
FORCEPROP 1 LAST PATH I67
J 0
(-5975 4950);
DISPLAY 0.978723 (-5975 4950);
PAINT WHITE (-5975 4950);
DISPLAY INVISIBLE (-5975 4950);
FORCEADD Q_RES..1
(-5925 4650);
FORCEPROP 1 LAST LOCATION PR177
J 0
(-5975 4700);
DISPLAY 0.489362 (-5975 4700);
PAINT SKYBLUE (-5975 4700);
FORCEPROP 0 LAST $SEC 1
J 0
(-5975 4725);
DISPLAY 0.680851 (-5975 4725);
PAINT MONO (-5975 4725);
DISPLAY INVISIBLE (-5975 4725);
FORCEPROP 0 LAST CDS_SEC 1
J 0
(-5975 4725);
DISPLAY 1.021277 (-5975 4725);
DISPLAY INVISIBLE (-5975 4725);
FORCEPROP 1 LASTPIN (-6025 4650) $PN 1
J 0
(-6013 4662);
DISPLAY 0.489362 (-6013 4662);
PAINT MONO (-6013 4662);
FORCEPROP 1 LASTPIN (-5825 4650) $PN 2
J 0
(-5863 4662);
DISPLAY 0.489362 (-5863 4662);
PAINT MONO (-5863 4662);
FORCEPROP 1 LAST WATTAGE 1/16W
J 0
(-5825 4600);
DISPLAY 0.489362 (-5825 4600);
PAINT SKYBLUE (-5825 4600);
FORCEPROP 1 LAST MATERIAL CHIP
J 0
(-6175 4575);
DISPLAY 0.489362 (-6175 4575);
PAINT SKYBLUE (-6175 4575);
FORCEPROP 1 LAST TOLERANCE 5%
J 0
(-5800 4675);
DISPLAY 0.489362 (-5800 4675);
PAINT SKYBLUE (-5800 4675);
FORCEPROP 1 LAST VALUE 0
J 2
(-6050 4675);
DISPLAY 0.489362 (-6050 4675);
PAINT SKYBLUE (-6050 4675);
FORCEPROP 1 LAST PART_NUMBER CS00002JB38
J 0
(-6175 4600);
DISPLAY 0.489362 (-6175 4600);
PAINT SKYBLUE (-6175 4600);
FORCEPROP 1 LAST PACK_TYPE 0402LF
J 0
(-5825 4575);
DISPLAY 0.489362 (-5825 4575);
PAINT SKYBLUE (-5825 4575);
FORCEPROP 2 LAST CDS_LIB pure_quanta
J 0
(-5925 4650);
DISPLAY INVISIBLE (-5925 4650);
FORCEPROP 1 LAST PATH I68
J 0
(-5975 4800);
DISPLAY 0.978723 (-5975 4800);
PAINT WHITE (-5975 4800);
DISPLAY INVISIBLE (-5975 4800);
FORCEADD RAA229620GNPHA0..1
(-4300 3350);
FORCEPROP 1 LAST LOCATION PU25
J 0
(-4850 6375);
DISPLAY 0.489362 (-4850 6375);
PAINT SKYBLUE (-4850 6375);
FORCEPROP 2 LAST SEC 1
J 0
(-4850 6550);
DISPLAY 0.680851 (-4850 6550);
PAINT MONO (-4850 6550);
DISPLAY INVISIBLE (-4850 6550);
FORCEPROP 2 LASTPIN (-3650 1700) $PN 38
J 0
(-3640 1710);
DISPLAY 0.489362 (-3640 1710);
PAINT MONO (-3640 1710);
FORCEPROP 2 LASTPIN (-3650 2000) $PN 37
J 0
(-3640 2010);
DISPLAY 0.489362 (-3640 2010);
PAINT MONO (-3640 2010);
FORCEPROP 2 LASTPIN (-3650 2300) $PN 36
J 0
(-3640 2310);
DISPLAY 0.489362 (-3640 2310);
PAINT MONO (-3640 2310);
FORCEPROP 2 LASTPIN (-3650 2600) $PN 35
J 0
(-3640 2610);
DISPLAY 0.489362 (-3640 2610);
PAINT MONO (-3640 2610);
FORCEPROP 2 LASTPIN (-3650 2900) $PN 34
J 0
(-3640 2910);
DISPLAY 0.489362 (-3640 2910);
PAINT MONO (-3640 2910);
FORCEPROP 2 LASTPIN (-3650 3200) $PN 33
J 0
(-3640 3210);
DISPLAY 0.489362 (-3640 3210);
PAINT MONO (-3640 3210);
FORCEPROP 2 LASTPIN (-3650 3500) $PN 32
J 0
(-3640 3510);
DISPLAY 0.489362 (-3640 3510);
PAINT MONO (-3640 3510);
FORCEPROP 2 LASTPIN (-3650 3800) $PN 31
J 0
(-3640 3810);
DISPLAY 0.489362 (-3640 3810);
PAINT MONO (-3640 3810);
FORCEPROP 2 LASTPIN (-3650 4100) $PN 30
J 0
(-3640 4110);
DISPLAY 0.489362 (-3640 4110);
PAINT MONO (-3640 4110);
FORCEPROP 2 LASTPIN (-3650 4400) $PN 29
J 0
(-3640 4410);
DISPLAY 0.489362 (-3640 4410);
PAINT MONO (-3640 4410);
FORCEPROP 2 LASTPIN (-3650 4700) $PN 28
J 0
(-3640 4710);
DISPLAY 0.489362 (-3640 4710);
PAINT MONO (-3640 4710);
FORCEPROP 2 LASTPIN (-3650 5000) $PN 27
J 0
(-3640 5010);
DISPLAY 0.489362 (-3640 5010);
PAINT MONO (-3640 5010);
FORCEPROP 2 LASTPIN (-5000 5950) $PN 17
J 2
(-5010 5960);
DISPLAY 0.489362 (-5010 5960);
PAINT MONO (-5010 5960);
FORCEPROP 2 LASTPIN (-5000 1350) $PN 42
J 2
(-5010 1360);
DISPLAY 0.489362 (-5010 1360);
PAINT MONO (-5010 1360);
FORCEPROP 2 LASTPIN (-5000 4650) $PN 15
J 2
(-5010 4660);
DISPLAY 0.489362 (-5010 4660);
PAINT MONO (-5010 4660);
FORCEPROP 2 LASTPIN (-5000 2100) $PN 41
J 2
(-5010 2110);
DISPLAY 0.489362 (-5010 2110);
PAINT MONO (-5010 2110);
FORCEPROP 2 LASTPIN (-5000 6100) $PN 16
J 2
(-5010 6110);
DISPLAY 0.489362 (-5010 6110);
PAINT MONO (-5010 6110);
FORCEPROP 2 LASTPIN (-5000 850) $PN 20
J 2
(-5010 860);
DISPLAY 0.489362 (-5010 860);
PAINT MONO (-5010 860);
FORCEPROP 2 LASTPIN (-5000 4950) $PN 14
J 2
(-5010 4960);
DISPLAY 0.489362 (-5010 4960);
PAINT MONO (-5010 4960);
FORCEPROP 2 LASTPIN (-5000 4800) $PN 13
J 2
(-5010 4810);
DISPLAY 0.489362 (-5010 4810);
PAINT MONO (-5010 4810);
FORCEPROP 2 LASTPIN (-3650 1800) $PN 1
J 0
(-3640 1810);
DISPLAY 0.489362 (-3640 1810);
PAINT MONO (-3640 1810);
FORCEPROP 2 LASTPIN (-3650 2100) $PN 2
J 0
(-3640 2110);
DISPLAY 0.489362 (-3640 2110);
PAINT MONO (-3640 2110);
FORCEPROP 2 LASTPIN (-3650 2400) $PN 3
J 0
(-3640 2410);
DISPLAY 0.489362 (-3640 2410);
PAINT MONO (-3640 2410);
FORCEPROP 2 LASTPIN (-3650 2700) $PN 4
J 0
(-3640 2710);
DISPLAY 0.489362 (-3640 2710);
PAINT MONO (-3640 2710);
FORCEPROP 2 LASTPIN (-3650 3000) $PN 5
J 0
(-3640 3010);
DISPLAY 0.489362 (-3640 3010);
PAINT MONO (-3640 3010);
FORCEPROP 2 LASTPIN (-3650 3300) $PN 6
J 0
(-3640 3310);
DISPLAY 0.489362 (-3640 3310);
PAINT MONO (-3640 3310);
FORCEPROP 2 LASTPIN (-3650 3600) $PN 7
J 0
(-3640 3610);
DISPLAY 0.489362 (-3640 3610);
PAINT MONO (-3640 3610);
FORCEPROP 2 LASTPIN (-3650 3900) $PN 8
J 0
(-3640 3910);
DISPLAY 0.489362 (-3640 3910);
PAINT MONO (-3640 3910);
FORCEPROP 2 LASTPIN (-3650 4200) $PN 9
J 0
(-3640 4210);
DISPLAY 0.489362 (-3640 4210);
PAINT MONO (-3640 4210);
FORCEPROP 2 LASTPIN (-3650 4500) $PN 10
J 0
(-3640 4510);
DISPLAY 0.489362 (-3640 4510);
PAINT MONO (-3640 4510);
FORCEPROP 2 LASTPIN (-3650 4800) $PN 11
J 0
(-3640 4810);
DISPLAY 0.489362 (-3640 4810);
PAINT MONO (-3640 4810);
FORCEPROP 2 LASTPIN (-3650 5100) $PN 12
J 0
(-3640 5110);
DISPLAY 0.489362 (-3640 5110);
PAINT MONO (-3640 5110);
FORCEPROP 2 LASTPIN (-5000 2250) $PN 18
J 2
(-5010 2260);
DISPLAY 0.489362 (-5010 2260);
PAINT MONO (-5010 2260);
FORCEPROP 2 LASTPIN (-5000 3800) $PN 26
J 2
(-5010 3810);
DISPLAY 0.489362 (-5010 3810);
PAINT MONO (-5010 3810);
FORCEPROP 2 LASTPIN (-5000 2700) $PN 39
J 2
(-5010 2710);
DISPLAY 0.489362 (-5010 2710);
PAINT MONO (-5010 2710);
FORCEPROP 2 LASTPIN (-5000 5650) $PN 22
J 2
(-5010 5660);
DISPLAY 0.489362 (-5010 5660);
PAINT MONO (-5010 5660);
FORCEPROP 2 LASTPIN (-5000 5500) $PN 21
J 2
(-5010 5510);
DISPLAY 0.489362 (-5010 5510);
PAINT MONO (-5010 5510);
FORCEPROP 2 LASTPIN (-5000 5200) $PN 24
J 2
(-5010 5210);
DISPLAY 0.489362 (-5010 5210);
PAINT MONO (-5010 5210);
FORCEPROP 2 LASTPIN (-5000 5350) $PN 23
J 2
(-5010 5360);
DISPLAY 0.489362 (-5010 5360);
PAINT MONO (-5010 5360);
FORCEPROP 2 LASTPIN (-3650 900) $PN 44
J 0
(-3640 910);
DISPLAY 0.489362 (-3640 910);
PAINT MONO (-3640 910);
FORCEPROP 2 LASTPIN (-3650 1200) $PN 43
J 0
(-3640 1210);
DISPLAY 0.489362 (-3640 1210);
PAINT MONO (-3640 1210);
FORCEPROP 2 LASTPIN (-5000 550) $PN TH
J 2
(-5010 560);
DISPLAY 0.489362 (-5010 560);
PAINT MONO (-5010 560);
FORCEPROP 2 LASTPIN (-3650 6100) $PN 47
J 0
(-3640 6110);
DISPLAY 0.489362 (-3640 6110);
PAINT MONO (-3640 6110);
FORCEPROP 2 LASTPIN (-3650 5800) $PN 48
J 0
(-3640 5810);
DISPLAY 0.489362 (-3640 5810);
PAINT MONO (-3640 5810);
FORCEPROP 2 LASTPIN (-5000 1850) $PN 19
J 2
(-5010 1860);
DISPLAY 0.489362 (-5010 1860);
PAINT MONO (-5010 1860);
FORCEPROP 2 LASTPIN (-5000 650) $PN 46
J 2
(-5010 660);
DISPLAY 0.489362 (-5010 660);
PAINT MONO (-5010 660);
FORCEPROP 2 LASTPIN (-5000 750) $PN 45
J 2
(-5010 760);
DISPLAY 0.489362 (-5010 760);
PAINT MONO (-5010 760);
FORCEPROP 2 LASTPIN (-5000 4050) $PN 25
J 2
(-5010 4060);
DISPLAY 0.489362 (-5010 4060);
PAINT MONO (-5010 4060);
FORCEPROP 2 LASTPIN (-5000 2950) $PN 40
J 2
(-5010 2960);
DISPLAY 0.489362 (-5010 2960);
PAINT MONO (-5010 2960);
FORCEPROP 1 LAST PART_NUMBER AR0T6GPV005
J 0
(-4850 6300);
DISPLAY 0.489362 (-4850 6300);
PAINT SKYBLUE (-4850 6300);
FORCEPROP 2 LAST VALUE RAA229620GNP#HA0
J 0
(-4850 6450);
DISPLAY 0.489362 (-4850 6450);
PAINT SKYBLUE (-4850 6450);
FORCEPROP 1 LAST MATERIAL IC
J 0
(-4850 6225);
DISPLAY 0.489362 (-4850 6225);
PAINT SKYBLUE (-4850 6225);
FORCEPROP 2 LAST PART_TYPE SMLF
J 0
(-4850 6500);
DISPLAY 1.021277 (-4850 6500);
FORCEPROP 1 LAST PATH I7
J 0
(-4300 3350);
DISPLAY 0.723404 (-4300 3350);
PAINT GREEN (-4300 3350);
DISPLAY INVISIBLE (-4300 3350);
FORCEPROP 2 LAST SEC_TYPE 
J 0
(-4850 6550);
DISPLAY 1.021277 (-4850 6550);
DISPLAY INVISIBLE (-4850 6550);
FORCEPROP 1 LAST CDS_LMAN_SYM_OUTLINE -550,2850,500,-2850
J 0
(-4300 3350);
DISPLAY 0.468085 (-4300 3350);
PAINT GREEN (-4300 3350);
DISPLAY INVISIBLE (-4300 3350);
FORCEPROP 1 LAST NEEDS_NO_SIZE TRUE
J 0
(-4300 3350);
DISPLAY 0.723404 (-4300 3350);
PAINT GREEN (-4300 3350);
DISPLAY INVISIBLE (-4300 3350);
FORCEPROP 2 LAST CDS_LIB pure_quanta
J 0
(-4300 3350);
DISPLAY INVISIBLE (-4300 3350);
FORCEADD OFFPAGE..4
R 2
(-6750 4950);
FORCEPROP 2 LAST $XR1 193 
J 0
(-7122 4950);
DISPLAY 0.638298 (-7122 4950);
PAINT MONO (-7122 4950);
FORCEPROP 2 LAST $XR0 118 
J 0
(-7002 4950);
DISPLAY 0.638298 (-7002 4950);
PAINT MONO (-7002 4950);
FORCEPROP 2 LAST CDS_LIB standard
J 0
(-6750 4950);
DISPLAY INVISIBLE (-6750 4950);
FORCEPROP 1 LAST OFFPAGE TRUE
J 2
(-7075 4825);
DISPLAY 0.872340 (-7075 4825);
PAINT GREEN (-7075 4825);
DISPLAY INVISIBLE (-7075 4825);
FORCEPROP 1 LAST COMMENT_BODY TRUE
J 2
(-6725 4850);
DISPLAY 0.872340 (-6725 4850);
PAINT GREEN (-6725 4850);
DISPLAY INVISIBLE (-6725 4850);
FORCEPROP 2 LAST PATH I73
J 0
(-6700 5025);
DISPLAY 1.021277 (-6700 5025);
DISPLAY INVISIBLE (-6700 5025);
FORCEADD OFFPAGE..3
R 2
(-6750 4800);
FORCEPROP 2 LAST $XR1 193 
J 0
(-7150 4800);
DISPLAY 0.638298 (-7150 4800);
PAINT MONO (-7150 4800);
FORCEPROP 2 LAST $XR0 118 
J 0
(-7030 4800);
DISPLAY 0.638298 (-7030 4800);
PAINT MONO (-7030 4800);
FORCEPROP 2 LAST CDS_LIB standard
J 0
(-6750 4800);
DISPLAY INVISIBLE (-6750 4800);
FORCEPROP 1 LAST OFFPAGE TRUE
J 2
(-7075 4675);
DISPLAY 0.872340 (-7075 4675);
PAINT GREEN (-7075 4675);
DISPLAY INVISIBLE (-7075 4675);
FORCEPROP 1 LAST COMMENT_BODY TRUE
J 2
(-6700 4700);
DISPLAY 0.872340 (-6700 4700);
PAINT GREEN (-6700 4700);
DISPLAY INVISIBLE (-6700 4700);
FORCEPROP 2 LAST PATH I74
J 0
(-6700 4875);
DISPLAY 1.021277 (-6700 4875);
DISPLAY INVISIBLE (-6700 4875);
FORCEADD OFFPAGE..2
R 2
(-6750 4650);
FORCEPROP 2 LAST $XR1 81 
J 0
(-7064 4650);
DISPLAY 0.638298 (-7064 4650);
PAINT MONO (-7064 4650);
FORCEPROP 2 LAST $XR0 82 
J 0
(-6974 4650);
DISPLAY 0.638298 (-6974 4650);
PAINT MONO (-6974 4650);
FORCEPROP 2 LAST CDS_LIB standard
J 0
(-6750 4650);
DISPLAY INVISIBLE (-6750 4650);
FORCEPROP 1 LAST OFFPAGE TRUE
J 2
(-7075 4525);
DISPLAY 0.872340 (-7075 4525);
PAINT GREEN (-7075 4525);
DISPLAY INVISIBLE (-7075 4525);
FORCEPROP 1 LAST COMMENT_BODY TRUE
J 2
(-6705 4555);
DISPLAY 0.872340 (-6705 4555);
PAINT GREEN (-6705 4555);
DISPLAY INVISIBLE (-6705 4555);
FORCEPROP 2 LAST PATH I75
J 0
(-6700 4725);
DISPLAY 1.021277 (-6700 4725);
DISPLAY INVISIBLE (-6700 4725);
FORCEADD Q_CAP..1
(-5750 3925);
FORCEPROP 1 LAST LOCATION PC244
J 0
(-5700 3975);
DISPLAY 0.489362 (-5700 3975);
PAINT SKYBLUE (-5700 3975);
FORCEPROP 0 LAST $SEC 1
J 0
(-5700 4000);
DISPLAY 0.680851 (-5700 4000);
PAINT MONO (-5700 4000);
DISPLAY INVISIBLE (-5700 4000);
FORCEPROP 0 LAST CDS_SEC 1
J 0
(-5700 4000);
DISPLAY 1.021277 (-5700 4000);
DISPLAY INVISIBLE (-5700 4000);
FORCEPROP 1 LASTPIN (-5750 4025) $PN 1
J 0
(-5740 4005);
DISPLAY 0.489362 (-5740 4005);
PAINT MONO (-5740 4005);
FORCEPROP 1 LASTPIN (-5750 3825) $PN 2
J 0
(-5740 3805);
DISPLAY 0.489362 (-5740 3805);
PAINT MONO (-5740 3805);
FORCEPROP 1 LAST MATERIAL X7R
J 0
(-5700 3875);
DISPLAY 0.489362 (-5700 3875);
PAINT SKYBLUE (-5700 3875);
FORCEPROP 1 LAST TOLERANCE 10%
J 0
(-5700 3900);
DISPLAY 0.489362 (-5700 3900);
PAINT SKYBLUE (-5700 3900);
FORCEPROP 1 LAST VALUE 3300PF
J 0
(-5700 3950);
DISPLAY 0.489362 (-5700 3950);
PAINT SKYBLUE (-5700 3950);
FORCEPROP 1 LAST PART_NUMBER TMP_QCH2336K1B12
J 0
(-5700 3850);
DISPLAY 0.489362 (-5700 3850);
PAINT SKYBLUE (-5700 3850);
FORCEPROP 1 LAST VOLTAGE 50V
J 0
(-5700 3925);
DISPLAY 0.489362 (-5700 3925);
PAINT SKYBLUE (-5700 3925);
FORCEPROP 1 LAST PACK_TYPE 0402
J 0
(-5700 3825);
DISPLAY 0.489362 (-5700 3825);
PAINT SKYBLUE (-5700 3825);
FORCEPROP 2 LAST CDS_LIB pure_quanta
J 0
(-5750 3925);
DISPLAY INVISIBLE (-5750 3925);
FORCEPROP 1 LAST PATH I76
J 0
(-5700 4075);
DISPLAY 0.978723 (-5700 4075);
PAINT WHITE (-5700 4075);
DISPLAY INVISIBLE (-5700 4075);
FORCEADD Q_RES..1
(-6025 4050);
FORCEPROP 1 LAST LOCATION PR173
J 0
(-6075 4100);
DISPLAY 0.489362 (-6075 4100);
PAINT SKYBLUE (-6075 4100);
FORCEPROP 0 LAST $SEC 1
J 0
(-6075 4125);
DISPLAY 0.680851 (-6075 4125);
PAINT MONO (-6075 4125);
DISPLAY INVISIBLE (-6075 4125);
FORCEPROP 0 LAST CDS_SEC 1
J 0
(-6075 4125);
DISPLAY 1.021277 (-6075 4125);
DISPLAY INVISIBLE (-6075 4125);
FORCEPROP 1 LASTPIN (-6125 4050) $PN 1
J 0
(-6113 4062);
DISPLAY 0.489362 (-6113 4062);
PAINT MONO (-6113 4062);
FORCEPROP 1 LASTPIN (-5925 4050) $PN 2
J 0
(-5963 4062);
DISPLAY 0.489362 (-5963 4062);
PAINT MONO (-5963 4062);
FORCEPROP 1 LAST WATTAGE 1/16W
J 0
(-5925 4000);
DISPLAY 0.489362 (-5925 4000);
PAINT SKYBLUE (-5925 4000);
FORCEPROP 1 LAST MATERIAL CHIP
J 0
(-6350 3975);
DISPLAY 0.489362 (-6350 3975);
PAINT SKYBLUE (-6350 3975);
FORCEPROP 1 LAST TOLERANCE 1%
J 0
(-5900 4075);
DISPLAY 0.489362 (-5900 4075);
PAINT SKYBLUE (-5900 4075);
FORCEPROP 1 LAST VALUE 10
J 2
(-6150 4075);
DISPLAY 0.489362 (-6150 4075);
PAINT SKYBLUE (-6150 4075);
FORCEPROP 1 LAST PART_NUMBER TMP_QCS01002FB21
J 0
(-6350 4000);
DISPLAY 0.489362 (-6350 4000);
PAINT SKYBLUE (-6350 4000);
FORCEPROP 1 LAST PACK_TYPE 0402LF
J 0
(-5925 3975);
DISPLAY 0.489362 (-5925 3975);
PAINT SKYBLUE (-5925 3975);
FORCEPROP 2 LAST CDS_LIB pure_quanta
J 0
(-6025 4050);
DISPLAY INVISIBLE (-6025 4050);
FORCEPROP 1 LAST PATH I77
J 0
(-6075 4200);
DISPLAY 0.978723 (-6075 4200);
PAINT WHITE (-6075 4200);
DISPLAY INVISIBLE (-6075 4200);
FORCEADD OFFPAGE..4
R 2
(-7850 4050);
FORCEPROP 2 LAST $XR0 54 
J 0
(-8131 4050);
DISPLAY 0.638298 (-8131 4050);
PAINT MONO (-8131 4050);
FORCEPROP 2 LAST CDS_LIB standard
J 2
(-7850 4050);
DISPLAY INVISIBLE (-7850 4050);
FORCEPROP 1 LAST OFFPAGE TRUE
J 2
(-8175 3925);
DISPLAY 0.872340 (-8175 3925);
PAINT GREEN (-8175 3925);
DISPLAY INVISIBLE (-8175 3925);
FORCEPROP 1 LAST COMMENT_BODY TRUE
J 2
(-7825 3950);
DISPLAY 0.872340 (-7825 3950);
PAINT GREEN (-7825 3950);
DISPLAY INVISIBLE (-7825 3950);
FORCEPROP 2 LAST PATH I79
J 2
(-8025 4125);
DISPLAY 1.021277 (-8025 4125);
DISPLAY INVISIBLE (-8025 4125);
FORCEADD Q_CAP..1
(-2900 6125);
FORCEPROP 1 LAST LOCATION PC252
J 0
(-2850 6225);
DISPLAY 0.489362 (-2850 6225);
PAINT SKYBLUE (-2850 6225);
FORCEPROP 0 LAST $SEC 1
J 0
(-2850 6250);
DISPLAY 0.680851 (-2850 6250);
PAINT MONO (-2850 6250);
DISPLAY INVISIBLE (-2850 6250);
FORCEPROP 0 LAST CDS_SEC 1
J 0
(-2850 6250);
DISPLAY 1.021277 (-2850 6250);
DISPLAY INVISIBLE (-2850 6250);
FORCEPROP 1 LASTPIN (-2900 6225) $PN 1
J 0
(-2890 6205);
DISPLAY 0.489362 (-2890 6205);
PAINT MONO (-2890 6205);
FORCEPROP 1 LASTPIN (-2900 6025) $PN 2
J 0
(-2890 6005);
DISPLAY 0.489362 (-2890 6005);
PAINT MONO (-2890 6005);
FORCEPROP 1 LAST MATERIAL X6S
J 0
(-2850 6025);
DISPLAY 0.489362 (-2850 6025);
PAINT SKYBLUE (-2850 6025);
FORCEPROP 1 LAST TOLERANCE 10%
J 0
(-2850 6075);
DISPLAY 0.489362 (-2850 6075);
PAINT SKYBLUE (-2850 6075);
FORCEPROP 1 LAST VALUE 1UF
J 0
(-2850 6175);
DISPLAY 0.489362 (-2850 6175);
PAINT SKYBLUE (-2850 6175);
FORCEPROP 1 LAST PART_NUMBER CH5103KEB01
J 0
(-2850 5975);
DISPLAY 0.489362 (-2850 5975);
PAINT SKYBLUE (-2850 5975);
FORCEPROP 1 LAST VOLTAGE 16V
J 0
(-2850 6125);
DISPLAY 0.489362 (-2850 6125);
PAINT SKYBLUE (-2850 6125);
FORCEPROP 1 LAST PACK_TYPE C0402
J 0
(-2850 5925);
DISPLAY 0.489362 (-2850 5925);
PAINT SKYBLUE (-2850 5925);
FORCEPROP 2 LAST CDS_LIB pure_quanta
J 0
(-2900 6125);
DISPLAY INVISIBLE (-2900 6125);
FORCEPROP 1 LAST PATH I8
J 0
(-2850 6275);
DISPLAY 0.978723 (-2850 6275);
PAINT WHITE (-2850 6275);
DISPLAY INVISIBLE (-2850 6275);
FORCEADD OFFPAGE..4
R 2
(-7850 3800);
FORCEPROP 2 LAST $XR1 186 
J 0
(-8251 3800);
DISPLAY 0.638298 (-8251 3800);
PAINT MONO (-8251 3800);
FORCEPROP 2 LAST $XR0 54 
J 0
(-8131 3800);
DISPLAY 0.638298 (-8131 3800);
PAINT MONO (-8131 3800);
FORCEPROP 2 LAST CDS_LIB standard
J 0
(-7850 3800);
DISPLAY INVISIBLE (-7850 3800);
FORCEPROP 1 LAST OFFPAGE TRUE
J 2
(-8175 3675);
DISPLAY 0.872340 (-8175 3675);
PAINT GREEN (-8175 3675);
DISPLAY INVISIBLE (-8175 3675);
FORCEPROP 1 LAST COMMENT_BODY TRUE
J 2
(-7825 3700);
DISPLAY 0.872340 (-7825 3700);
PAINT GREEN (-7825 3700);
DISPLAY INVISIBLE (-7825 3700);
FORCEPROP 2 LAST PATH I80
J 0
(-7800 3875);
DISPLAY 1.021277 (-7800 3875);
DISPLAY INVISIBLE (-7800 3875);
FORCEADD Q_RES..2
(-7100 4250);
FORCEPROP 1 LAST LOCATION PR161
J 0
(-7050 4375);
DISPLAY 0.489362 (-7050 4375);
PAINT SKYBLUE (-7050 4375);
FORCEPROP 0 LAST $SEC 1
J 0
(-7050 4400);
DISPLAY 0.680851 (-7050 4400);
PAINT MONO (-7050 4400);
DISPLAY INVISIBLE (-7050 4400);
FORCEPROP 0 LAST CDS_SEC 1
J 0
(-7050 4400);
DISPLAY 1.021277 (-7050 4400);
DISPLAY INVISIBLE (-7050 4400);
FORCEPROP 1 LASTPIN (-7100 4350) $PN 1
J 0
(-7095 4312);
DISPLAY 0.489362 (-7095 4312);
PAINT MONO (-7095 4312);
FORCEPROP 1 LASTPIN (-7100 4150) $PN 2
J 0
(-7095 4160);
DISPLAY 0.489362 (-7095 4160);
PAINT MONO (-7095 4160);
FORCEPROP 1 LAST WATTAGE 1/16W
J 0
(-7050 4225);
DISPLAY 0.489362 (-7050 4225);
PAINT SKYBLUE (-7050 4225);
FORCEPROP 1 LAST MATERIAL CHIP
J 0
(-7050 4175);
DISPLAY 0.489362 (-7050 4175);
PAINT SKYBLUE (-7050 4175);
FORCEPROP 1 LAST PART_NUMBER CS04992FB31
J 0
(-7050 4125);
DISPLAY 0.489362 (-7050 4125);
PAINT SKYBLUE (-7050 4125);
FORCEPROP 1 LAST PACK_TYPE 0402LF
J 0
(-7050 4075);
DISPLAY 0.489362 (-7050 4075);
PAINT SKYBLUE (-7050 4075);
FORCEPROP 1 LAST VALUE 49.9
J 0
(-7050 4325);
DISPLAY 0.489362 (-7050 4325);
PAINT SKYBLUE (-7050 4325);
FORCEPROP 1 LAST TOLERANCE 1%
J 0
(-7050 4275);
DISPLAY 0.489362 (-7050 4275);
PAINT SKYBLUE (-7050 4275);
FORCEPROP 2 LAST CDS_LIB pure_quanta
J 0
(-7100 4250);
DISPLAY INVISIBLE (-7100 4250);
FORCEPROP 1 LAST PATH I81
J 0
(-7050 4425);
DISPLAY 0.978723 (-7050 4425);
PAINT WHITE (-7050 4425);
DISPLAY INVISIBLE (-7050 4425);
FORCEADD Q_RES..2
(-7100 3625);
FORCEPROP 1 LAST LOCATION PR162
J 0
(-7050 3750);
DISPLAY 0.489362 (-7050 3750);
PAINT SKYBLUE (-7050 3750);
FORCEPROP 0 LAST $SEC 1
J 0
(-7050 3775);
DISPLAY 0.680851 (-7050 3775);
PAINT MONO (-7050 3775);
DISPLAY INVISIBLE (-7050 3775);
FORCEPROP 0 LAST CDS_SEC 1
J 0
(-7050 3775);
DISPLAY 1.021277 (-7050 3775);
DISPLAY INVISIBLE (-7050 3775);
FORCEPROP 1 LASTPIN (-7100 3725) $PN 1
J 0
(-7095 3687);
DISPLAY 0.489362 (-7095 3687);
PAINT MONO (-7095 3687);
FORCEPROP 1 LASTPIN (-7100 3525) $PN 2
J 0
(-7095 3535);
DISPLAY 0.489362 (-7095 3535);
PAINT MONO (-7095 3535);
FORCEPROP 1 LAST WATTAGE 1/16W
J 0
(-7050 3600);
DISPLAY 0.489362 (-7050 3600);
PAINT SKYBLUE (-7050 3600);
FORCEPROP 1 LAST MATERIAL CHIP
J 0
(-7050 3550);
DISPLAY 0.489362 (-7050 3550);
PAINT SKYBLUE (-7050 3550);
FORCEPROP 1 LAST PART_NUMBER CS04992FB31
J 0
(-7050 3500);
DISPLAY 0.489362 (-7050 3500);
PAINT SKYBLUE (-7050 3500);
FORCEPROP 1 LAST PACK_TYPE 0402LF
J 0
(-7050 3450);
DISPLAY 0.489362 (-7050 3450);
PAINT SKYBLUE (-7050 3450);
FORCEPROP 1 LAST VALUE 49.9
J 0
(-7050 3700);
DISPLAY 0.489362 (-7050 3700);
PAINT SKYBLUE (-7050 3700);
FORCEPROP 1 LAST TOLERANCE 1%
J 0
(-7050 3650);
DISPLAY 0.489362 (-7050 3650);
PAINT SKYBLUE (-7050 3650);
FORCEPROP 2 LAST CDS_LIB pure_quanta
J 0
(-7100 3625);
DISPLAY INVISIBLE (-7100 3625);
FORCEPROP 1 LAST PATH I82
J 0
(-7050 3800);
DISPLAY 0.978723 (-7050 3800);
PAINT WHITE (-7050 3800);
DISPLAY INVISIBLE (-7050 3800);
FORCEADD UNIVERSAL_GND..1
(-7100 3425);
FORCEPROP 3 LASTPIN (-7100 3475) SIG_NAME GND\g
J 0
(-7090 3485);
DISPLAY 0.659574 (-7090 3485);
PAINT MONO (-7090 3485);
DISPLAY INVISIBLE (-7090 3485);
FORCEPROP 2 LAST CDS_LIB pure_quanta_power
J 0
(-7100 3425);
DISPLAY INVISIBLE (-7100 3425);
FORCEPROP 1 LAST PATH I83
J 0
(-7025 3425);
DISPLAY 0.872340 (-7025 3425);
PAINT AQUA (-7025 3425);
DISPLAY INVISIBLE (-7025 3425);
FORCEPROP 1 LAST HDL_POWER GND
J 1
(-7075 3350);
DISPLAY 0.872340 (-7075 3350);
PAINT GREEN (-7075 3350);
DISPLAY INVISIBLE (-7075 3350);
FORCEADD VCC_CORE..1
(-7100 4450);
FORCEPROP 3 LASTPIN (-7100 4400) SIG_NAME PVDDCR_CPU0_P1\g
J 0
(-7090 4410);
DISPLAY 0.659574 (-7090 4410);
PAINT MONO (-7090 4410);
DISPLAY INVISIBLE (-7090 4410);
FORCEPROP 1 LAST HDL_POWER PVDDCR_CPU0_P1
J 1
(-7100 4500);
DISPLAY 0.489362 (-7100 4500);
PAINT GREEN (-7100 4500);
FORCEPROP 2 LAST CDS_LIB pure_quanta_power
J 0
(-7100 4450);
DISPLAY INVISIBLE (-7100 4450);
FORCEPROP 1 LAST PATH I84
J 0
(-7050 4475);
DISPLAY 0.872340 (-7050 4475);
PAINT AQUA (-7050 4475);
DISPLAY INVISIBLE (-7050 4475);
FORCEADD VCC_CORE..1
(-7100 3300);
FORCEPROP 3 LASTPIN (-7100 3250) SIG_NAME PVDDCR_SOC_P1\g
J 0
(-7090 3260);
DISPLAY 0.659574 (-7090 3260);
PAINT MONO (-7090 3260);
DISPLAY INVISIBLE (-7090 3260);
FORCEPROP 1 LAST HDL_POWER PVDDCR_SOC_P1
J 1
(-7100 3350);
DISPLAY 0.489362 (-7100 3350);
PAINT GREEN (-7100 3350);
FORCEPROP 2 LAST CDS_LIB pure_quanta_power
J 0
(-7100 3300);
DISPLAY INVISIBLE (-7100 3300);
FORCEPROP 1 LAST PATH I85
J 0
(-7050 3325);
DISPLAY 0.872340 (-7050 3325);
PAINT AQUA (-7050 3325);
DISPLAY INVISIBLE (-7050 3325);
FORCEADD Q_RES..2
(-7100 3125);
FORCEPROP 1 LAST LOCATION PR163
J 0
(-7050 3250);
DISPLAY 0.489362 (-7050 3250);
PAINT SKYBLUE (-7050 3250);
FORCEPROP 0 LAST $SEC 1
J 0
(-7050 3300);
DISPLAY 0.680851 (-7050 3300);
PAINT MONO (-7050 3300);
DISPLAY INVISIBLE (-7050 3300);
FORCEPROP 0 LAST CDS_SEC 1
J 0
(-7050 3300);
DISPLAY 1.021277 (-7050 3300);
DISPLAY INVISIBLE (-7050 3300);
FORCEPROP 1 LASTPIN (-7100 3225) $PN 1
J 0
(-7095 3187);
DISPLAY 0.489362 (-7095 3187);
PAINT MONO (-7095 3187);
FORCEPROP 1 LASTPIN (-7100 3025) $PN 2
J 0
(-7095 3035);
DISPLAY 0.489362 (-7095 3035);
PAINT MONO (-7095 3035);
FORCEPROP 1 LAST WATTAGE 1/16W
J 0
(-7050 3100);
DISPLAY 0.489362 (-7050 3100);
PAINT SKYBLUE (-7050 3100);
FORCEPROP 1 LAST MATERIAL CHIP
J 0
(-7050 3050);
DISPLAY 0.489362 (-7050 3050);
PAINT SKYBLUE (-7050 3050);
FORCEPROP 1 LAST PART_NUMBER CS04992FB31
J 0
(-7050 3000);
DISPLAY 0.489362 (-7050 3000);
PAINT SKYBLUE (-7050 3000);
FORCEPROP 1 LAST PACK_TYPE 0402LF
J 0
(-7050 2950);
DISPLAY 0.489362 (-7050 2950);
PAINT SKYBLUE (-7050 2950);
FORCEPROP 1 LAST VALUE 49.9
J 0
(-7050 3200);
DISPLAY 0.489362 (-7050 3200);
PAINT SKYBLUE (-7050 3200);
FORCEPROP 1 LAST TOLERANCE 1%
J 0
(-7050 3150);
DISPLAY 0.489362 (-7050 3150);
PAINT SKYBLUE (-7050 3150);
FORCEPROP 2 LAST CDS_LIB pure_quanta
J 0
(-7100 3125);
DISPLAY INVISIBLE (-7100 3125);
FORCEPROP 1 LAST PATH I86
J 0
(-7050 3300);
DISPLAY 0.978723 (-7050 3300);
PAINT WHITE (-7050 3300);
DISPLAY INVISIBLE (-7050 3300);
FORCEADD Q_CAP..1
(-5675 2825);
FORCEPROP 1 LAST LOCATION PC245
J 0
(-5625 2875);
DISPLAY 0.489362 (-5625 2875);
PAINT SKYBLUE (-5625 2875);
FORCEPROP 0 LAST $SEC 1
J 0
(-5625 2975);
DISPLAY 0.680851 (-5625 2975);
PAINT MONO (-5625 2975);
DISPLAY INVISIBLE (-5625 2975);
FORCEPROP 0 LAST CDS_SEC 1
J 0
(-5625 2975);
DISPLAY 1.021277 (-5625 2975);
DISPLAY INVISIBLE (-5625 2975);
FORCEPROP 1 LASTPIN (-5675 2925) $PN 1
J 0
(-5665 2905);
DISPLAY 0.489362 (-5665 2905);
PAINT MONO (-5665 2905);
FORCEPROP 1 LASTPIN (-5675 2725) $PN 2
J 0
(-5665 2705);
DISPLAY 0.489362 (-5665 2705);
PAINT MONO (-5665 2705);
FORCEPROP 1 LAST MATERIAL X7R
J 0
(-5625 2775);
DISPLAY 0.489362 (-5625 2775);
PAINT SKYBLUE (-5625 2775);
FORCEPROP 1 LAST TOLERANCE 10%
J 0
(-5625 2800);
DISPLAY 0.489362 (-5625 2800);
PAINT SKYBLUE (-5625 2800);
FORCEPROP 1 LAST VALUE 3300PF
J 0
(-5625 2850);
DISPLAY 0.489362 (-5625 2850);
PAINT SKYBLUE (-5625 2850);
FORCEPROP 1 LAST PART_NUMBER TMP_QCH2336K1B12
J 0
(-5625 2750);
DISPLAY 0.489362 (-5625 2750);
PAINT SKYBLUE (-5625 2750);
FORCEPROP 1 LAST VOLTAGE 50V
J 0
(-5625 2825);
DISPLAY 0.489362 (-5625 2825);
PAINT SKYBLUE (-5625 2825);
FORCEPROP 1 LAST PACK_TYPE 0402
J 0
(-5625 2725);
DISPLAY 0.489362 (-5625 2725);
PAINT SKYBLUE (-5625 2725);
FORCEPROP 2 LAST CDS_LIB pure_quanta
J 0
(-5675 2825);
DISPLAY INVISIBLE (-5675 2825);
FORCEPROP 1 LAST PATH I87
J 0
(-5625 2975);
DISPLAY 0.978723 (-5625 2975);
PAINT WHITE (-5625 2975);
DISPLAY INVISIBLE (-5625 2975);
FORCEADD Q_RES..1
(-5950 2950);
FORCEPROP 1 LAST LOCATION PR174
J 0
(-6000 3000);
DISPLAY 0.489362 (-6000 3000);
PAINT SKYBLUE (-6000 3000);
FORCEPROP 0 LAST $SEC 1
J 0
(-6000 3050);
DISPLAY 0.680851 (-6000 3050);
PAINT MONO (-6000 3050);
DISPLAY INVISIBLE (-6000 3050);
FORCEPROP 0 LAST CDS_SEC 1
J 0
(-6000 3050);
DISPLAY 1.021277 (-6000 3050);
DISPLAY INVISIBLE (-6000 3050);
FORCEPROP 1 LASTPIN (-6050 2950) $PN 1
J 0
(-6038 2962);
DISPLAY 0.489362 (-6038 2962);
PAINT MONO (-6038 2962);
FORCEPROP 1 LASTPIN (-5850 2950) $PN 2
J 0
(-5888 2962);
DISPLAY 0.489362 (-5888 2962);
PAINT MONO (-5888 2962);
FORCEPROP 1 LAST WATTAGE 1/16W
J 0
(-5850 2900);
DISPLAY 0.489362 (-5850 2900);
PAINT SKYBLUE (-5850 2900);
FORCEPROP 1 LAST MATERIAL CHIP
J 0
(-6275 2875);
DISPLAY 0.489362 (-6275 2875);
PAINT SKYBLUE (-6275 2875);
FORCEPROP 1 LAST TOLERANCE 1%
J 0
(-5825 2975);
DISPLAY 0.489362 (-5825 2975);
PAINT SKYBLUE (-5825 2975);
FORCEPROP 1 LAST VALUE 10
J 2
(-6075 2975);
DISPLAY 0.489362 (-6075 2975);
PAINT SKYBLUE (-6075 2975);
FORCEPROP 1 LAST PART_NUMBER TMP_QCS01002FB21
J 0
(-6275 2900);
DISPLAY 0.489362 (-6275 2900);
PAINT SKYBLUE (-6275 2900);
FORCEPROP 1 LAST PACK_TYPE 0402LF
J 0
(-5850 2875);
DISPLAY 0.489362 (-5850 2875);
PAINT SKYBLUE (-5850 2875);
FORCEPROP 2 LAST CDS_LIB pure_quanta
J 0
(-5950 2950);
DISPLAY INVISIBLE (-5950 2950);
FORCEPROP 1 LAST PATH I88
J 0
(-6000 3100);
DISPLAY 0.978723 (-6000 3100);
PAINT WHITE (-6000 3100);
DISPLAY INVISIBLE (-6000 3100);
FORCEADD Q_RES..2
(-7100 2525);
FORCEPROP 1 LAST LOCATION PR164
J 0
(-7050 2650);
DISPLAY 0.489362 (-7050 2650);
PAINT SKYBLUE (-7050 2650);
FORCEPROP 0 LAST $SEC 1
J 0
(-7050 2700);
DISPLAY 0.680851 (-7050 2700);
PAINT MONO (-7050 2700);
DISPLAY INVISIBLE (-7050 2700);
FORCEPROP 0 LAST CDS_SEC 1
J 0
(-7050 2700);
DISPLAY 1.021277 (-7050 2700);
DISPLAY INVISIBLE (-7050 2700);
FORCEPROP 1 LASTPIN (-7100 2625) $PN 1
J 0
(-7095 2587);
DISPLAY 0.489362 (-7095 2587);
PAINT MONO (-7095 2587);
FORCEPROP 1 LASTPIN (-7100 2425) $PN 2
J 0
(-7095 2435);
DISPLAY 0.489362 (-7095 2435);
PAINT MONO (-7095 2435);
FORCEPROP 1 LAST WATTAGE 1/16W
J 0
(-7050 2500);
DISPLAY 0.489362 (-7050 2500);
PAINT SKYBLUE (-7050 2500);
FORCEPROP 1 LAST MATERIAL CHIP
J 0
(-7050 2450);
DISPLAY 0.489362 (-7050 2450);
PAINT SKYBLUE (-7050 2450);
FORCEPROP 1 LAST PART_NUMBER CS04992FB31
J 0
(-7050 2400);
DISPLAY 0.489362 (-7050 2400);
PAINT SKYBLUE (-7050 2400);
FORCEPROP 1 LAST PACK_TYPE 0402LF
J 0
(-7050 2350);
DISPLAY 0.489362 (-7050 2350);
PAINT SKYBLUE (-7050 2350);
FORCEPROP 1 LAST VALUE 49.9
J 0
(-7050 2600);
DISPLAY 0.489362 (-7050 2600);
PAINT SKYBLUE (-7050 2600);
FORCEPROP 1 LAST TOLERANCE 1%
J 0
(-7050 2550);
DISPLAY 0.489362 (-7050 2550);
PAINT SKYBLUE (-7050 2550);
FORCEPROP 2 LAST CDS_LIB pure_quanta
J 0
(-7100 2525);
DISPLAY INVISIBLE (-7100 2525);
FORCEPROP 1 LAST PATH I90
J 0
(-7050 2700);
DISPLAY 0.978723 (-7050 2700);
PAINT WHITE (-7050 2700);
DISPLAY INVISIBLE (-7050 2700);
FORCEADD UNIVERSAL_GND..1
(-7100 2325);
FORCEPROP 3 LASTPIN (-7100 2375) SIG_NAME GND\g
J 0
(-7090 2385);
DISPLAY 0.659574 (-7090 2385);
PAINT MONO (-7090 2385);
DISPLAY INVISIBLE (-7090 2385);
FORCEPROP 2 LAST CDS_LIB pure_quanta_power
J 0
(-7100 2325);
DISPLAY INVISIBLE (-7100 2325);
FORCEPROP 1 LAST PATH I91
J 0
(-7025 2325);
DISPLAY 0.872340 (-7025 2325);
PAINT AQUA (-7025 2325);
DISPLAY INVISIBLE (-7025 2325);
FORCEPROP 1 LAST HDL_POWER GND
J 1
(-7075 2250);
DISPLAY 0.872340 (-7075 2250);
PAINT GREEN (-7075 2250);
DISPLAY INVISIBLE (-7075 2250);
FORCEADD OFFPAGE..4
R 2
(-7850 2950);
FORCEPROP 2 LAST $XR0 54 
J 0
(-8131 2950);
DISPLAY 0.638298 (-8131 2950);
PAINT MONO (-8131 2950);
FORCEPROP 2 LAST CDS_LIB standard
J 0
(-7850 2950);
DISPLAY INVISIBLE (-7850 2950);
FORCEPROP 1 LAST OFFPAGE TRUE
J 2
(-8175 2825);
DISPLAY 0.872340 (-8175 2825);
PAINT GREEN (-8175 2825);
DISPLAY INVISIBLE (-8175 2825);
FORCEPROP 1 LAST COMMENT_BODY TRUE
J 2
(-7825 2850);
DISPLAY 0.872340 (-7825 2850);
PAINT GREEN (-7825 2850);
DISPLAY INVISIBLE (-7825 2850);
FORCEPROP 2 LAST PATH I92
J 0
(-7800 3025);
DISPLAY 1.021277 (-7800 3025);
DISPLAY INVISIBLE (-7800 3025);
FORCEADD OFFPAGE..4
R 2
(-7850 2700);
FORCEPROP 2 LAST $XR1 186 
J 0
(-8251 2700);
DISPLAY 0.638298 (-8251 2700);
PAINT MONO (-8251 2700);
FORCEPROP 2 LAST $XR0 54 
J 0
(-8131 2700);
DISPLAY 0.638298 (-8131 2700);
PAINT MONO (-8131 2700);
FORCEPROP 2 LAST CDS_LIB standard
J 0
(-7850 2700);
DISPLAY INVISIBLE (-7850 2700);
FORCEPROP 1 LAST OFFPAGE TRUE
J 2
(-8175 2575);
DISPLAY 0.872340 (-8175 2575);
PAINT GREEN (-8175 2575);
DISPLAY INVISIBLE (-8175 2575);
FORCEPROP 1 LAST COMMENT_BODY TRUE
J 2
(-7825 2600);
DISPLAY 0.872340 (-7825 2600);
PAINT GREEN (-7825 2600);
DISPLAY INVISIBLE (-7825 2600);
FORCEPROP 2 LAST PATH I93
J 0
(-7800 2775);
DISPLAY 1.021277 (-7800 2775);
DISPLAY INVISIBLE (-7800 2775);
FORCEADD UNIVERSAL_GND..1
(-5100 450);
FORCEPROP 3 LASTPIN (-5100 500) SIG_NAME GND\g
J 0
(-5090 510);
DISPLAY 0.659574 (-5090 510);
PAINT MONO (-5090 510);
DISPLAY INVISIBLE (-5090 510);
FORCEPROP 2 LAST CDS_LIB pure_quanta_power
J 0
(-5100 450);
DISPLAY INVISIBLE (-5100 450);
FORCEPROP 1 LAST PATH I99
J 0
(-5025 450);
DISPLAY 0.872340 (-5025 450);
PAINT AQUA (-5025 450);
DISPLAY INVISIBLE (-5025 450);
FORCEPROP 1 LAST HDL_POWER GND
J 1
(-5075 375);
DISPLAY 0.872340 (-5075 375);
PAINT GREEN (-5075 375);
DISPLAY INVISIBLE (-5075 375);
FORCEADD DNS..1
(-7425 5950);
PAINT RED (-7425 5950);
FORCEPROP 2 LAST CDS_LIB mstr_misc
J 0
(-7425 5950);
DISPLAY INVISIBLE (-7425 5950);
FORCEPROP 1 LAST COMMENT_BODY TRUE
R 1
J 0
(-7350 5725);
DISPLAY 0.872340 (-7350 5725);
PAINT GREEN (-7350 5725);
DISPLAY INVISIBLE (-7350 5725);
FORCEADD DNS..1
(-5650 1225);
PAINT RED (-5650 1225);
FORCEPROP 2 LAST CDS_LIB mstr_misc
J 0
(-5650 1225);
DISPLAY INVISIBLE (-5650 1225);
FORCEPROP 1 LAST COMMENT_BODY TRUE
R 1
J 0
(-5575 1000);
DISPLAY 0.872340 (-5575 1000);
PAINT GREEN (-5575 1000);
DISPLAY INVISIBLE (-5575 1000);
FORCEADD DNS..1
(-7700 5950);
PAINT RED (-7700 5950);
FORCEPROP 2 LAST CDS_LIB mstr_misc
J 0
(-7700 5950);
DISPLAY INVISIBLE (-7700 5950);
FORCEPROP 1 LAST COMMENT_BODY TRUE
R 1
J 0
(-7625 5725);
DISPLAY 0.872340 (-7625 5725);
PAINT GREEN (-7625 5725);
DISPLAY INVISIBLE (-7625 5725);
FORCEADD DNS..1
(-8225 5000);
PAINT RED (-8225 5000);
FORCEPROP 2 LAST CDS_LIB mstr_misc
J 0
(-8225 5000);
DISPLAY INVISIBLE (-8225 5000);
FORCEPROP 1 LAST COMMENT_BODY TRUE
R 1
J 0
(-8150 4775);
DISPLAY 0.872340 (-8150 4775);
PAINT GREEN (-8150 4775);
DISPLAY INVISIBLE (-8150 4775);
FORCEADD DNS..1
(-5600 450);
PAINT RED (-5600 450);
FORCEPROP 2 LAST CDS_LIB mstr_misc
J 0
(-5600 450);
DISPLAY INVISIBLE (-5600 450);
FORCEPROP 1 LAST COMMENT_BODY TRUE
R 1
J 0
(-5525 225);
DISPLAY 0.872340 (-5525 225);
PAINT GREEN (-5525 225);
DISPLAY INVISIBLE (-5525 225);
FORCEADD DNS..1
(-7550 5000);
PAINT RED (-7550 5000);
FORCEPROP 2 LAST CDS_LIB mstr_misc
J 0
(-7550 5000);
DISPLAY INVISIBLE (-7550 5000);
FORCEPROP 1 LAST COMMENT_BODY TRUE
R 1
J 0
(-7475 4775);
DISPLAY 0.872340 (-7475 4775);
PAINT GREEN (-7475 4775);
DISPLAY INVISIBLE (-7475 4775);
FORCEADD QUANTA_TITLE_BLOCK_C..1
(0 0);
FORCEPROP 0 LAST CDS_CON_LAST_MODIFIED Fri Mar 11 14:53:32 2022
J 0
(-1885 15);
DISPLAY INVISIBLE (-1885 15);
FORCEPROP 1 LAST CUSTOM_TXT_CDS <CON_LAST_MODIFIED>
J 0
(-1885 15);
DISPLAY 0.978723 (-1885 15);
FORCEPROP 2 LAST CUSTOM_TXT_CDS <XR_PAGE_TITLE>
J 0
(-7890 5250);
DISPLAY 0.638298 (-7890 5250);
PAINT PINK (-7890 5250);
DISPLAY INVISIBLE (-7890 5250);
FORCEPROP 1 LAST CUSTOM_TXT_CDS <NAME_2>
J 0
(-3175 50);
FORCEPROP 1 LAST CUSTOM_TXT_CDS <NAME_1>
J 0
(-3175 175);
FORCEPROP 1 LAST CUSTOM_TXT_CDS <Q_NUMBER>
J 0
(-1403 103);
DISPLAY 1.212766 (-1403 103);
FORCEPROP 1 LAST CUSTOM_TXT_CDS <Q_PROJ>
J 0
(-2382 102);
DISPLAY 1.212766 (-2382 102);
FORCEPROP 1 LAST CUSTOM_TXT_CDS <Q_REV>
J 0
(-184 103);
DISPLAY 1.212766 (-184 103);
FORCEPROP 1 LAST CUSTOM_TXT_CDS <CON_PAGE_NUM> OF <CON_TOTAL_PAGES>
J 0
(-446 18);
DISPLAY 0.978723 (-446 18);
FORCEPROP 1 LAST Q_TITLE PVDDCR_CPU0_P1/PVDDCR_SOC_P1 VR CONTROLLER
J 0
(-9300 50);
DISPLAY 2.446809 (-9300 50);
PAINT GREEN (-9300 50);
FORCEPROP 1 LAST Q_DEPT BU9
J 1
(-3763 49);
DISPLAY 1.957447 (-3763 49);
PAINT GREEN (-3763 49);
FORCEPROP 2 LAST PAGE_BORDER TRUE
J 0
(-7890 5250);
DISPLAY 0.638298 (-7890 5250);
PAINT PINK (-7890 5250);
DISPLAY INVISIBLE (-7890 5250);
FORCEPROP 1 LAST CDS_LMAN_SYM_OUTLINE -9475,6775,100,-125
J 0
(0 0);
DISPLAY 0.468085 (0 0);
PAINT GREEN (0 0);
DISPLAY INVISIBLE (0 0);
FORCEPROP 2 LAST CDS_LIB pure_quanta
J 0
(0 0);
DISPLAY INVISIBLE (0 0);
FORCEPROP 1 LAST COMMENT_BODY TRUE
J 0
(12 -13);
DISPLAY 0.978723 (12 -13);
PAINT GREEN (12 -13);
DISPLAY INVISIBLE (12 -13);
FORCEPROP 2 LAST CDS_XR_PAGE_TITLE CR-186 : @T6G_MB_LIB.T6G(SCH_1):PAGE186
J 0
(-7890 5250);
DISPLAY 0.638298 (-7890 5250);
PAINT PINK (-7890 5250);
DISPLAY INVISIBLE (-7890 5250);
FORCEADD DNS..1
(-5250 6350);
PAINT RED (-5250 6350);
FORCEPROP 2 LAST CDS_LIB mstr_misc
J 0
(-5250 6350);
DISPLAY INVISIBLE (-5250 6350);
FORCEPROP 1 LAST COMMENT_BODY TRUE
R 1
J 0
(-5175 6125);
DISPLAY 0.872340 (-5175 6125);
PAINT GREEN (-5175 6125);
DISPLAY INVISIBLE (-5175 6125);
FORCEADD DNS..1
(-7825 5000);
PAINT RED (-7825 5000);
FORCEPROP 2 LAST CDS_LIB mstr_misc
J 0
(-7825 5000);
DISPLAY INVISIBLE (-7825 5000);
FORCEPROP 1 LAST COMMENT_BODY TRUE
R 1
J 0
(-7750 4775);
DISPLAY 0.872340 (-7750 4775);
PAINT GREEN (-7750 4775);
DISPLAY INVISIBLE (-7750 4775);
FORCEADD DNS..1
(-8350 5950);
PAINT RED (-8350 5950);
FORCEPROP 2 LAST CDS_LIB mstr_misc
J 0
(-8350 5950);
DISPLAY INVISIBLE (-8350 5950);
FORCEPROP 1 LAST COMMENT_BODY TRUE
R 1
J 0
(-8275 5725);
DISPLAY 0.872340 (-8275 5725);
PAINT GREEN (-8275 5725);
DISPLAY INVISIBLE (-8275 5725);
FORCEADD DNS..1
(-8050 5000);
PAINT RED (-8050 5000);
FORCEPROP 2 LAST CDS_LIB mstr_misc
J 0
(-8050 5000);
DISPLAY INVISIBLE (-8050 5000);
FORCEPROP 1 LAST COMMENT_BODY TRUE
R 1
J 0
(-7975 4775);
DISPLAY 0.872340 (-7975 4775);
PAINT GREEN (-7975 4775);
DISPLAY INVISIBLE (-7975 4775);
FORCEADD DNS..1
(-8000 5950);
PAINT RED (-8000 5950);
FORCEPROP 2 LAST CDS_LIB mstr_misc
J 0
(-8000 5950);
DISPLAY INVISIBLE (-8000 5950);
FORCEPROP 1 LAST COMMENT_BODY TRUE
R 1
J 0
(-7925 5725);
DISPLAY 0.872340 (-7925 5725);
PAINT GREEN (-7925 5725);
DISPLAY INVISIBLE (-7925 5725);
WIRE 16 -1 (-2900 5925)(-2900 6025);
WIRE 16 -1 (-5300 375)(-5300 300);
WIRE 16 -1 (-6950 550)(-6950 450);
WIRE 16 -1 (-6475 550)(-6475 450);
WIRE 16 -1 (-2925 5475)(-2925 5550);
WIRE 16 -1 (-8175 1125)(-8175 1050);
WIRE 16 -1 (-7825 4925)(-7825 4825);
WIRE 16 -1 (-7550 4925)(-7550 4825);
WIRE 16 -1 (-3250 5550)(-3250 5475);
WIRE 16 -1 (-3250 6025)(-3250 5925);
WIRE 16 -1 (-5575 1725)(-5325 1725);
WIRE 16 -1 (-8050 4925)(-8050 4825);
WIRE 16 -1 (-5625 350)(-5625 300);
WIRE 16 -1 (-3375 600)(-3375 475);
WIRE 16 -1 (-2750 825)(-2750 925);
WIRE 16 -1 (-8525 4925)(-8525 4825);
WIRE 16 -1 (-8250 4925)(-8250 4825);
WIRE 16 -1 (-7100 3525)(-7100 3475);
WIRE 16 -1 (-7100 4350)(-7100 4400);
WIRE 16 -1 (-7100 3225)(-7100 3250);
WIRE 16 -1 (-7100 2425)(-7100 2375);
WIRE 16 -1 (-5675 2725)(-5675 2700);
WIRE 16 -1 (-5675 2700)(-5000 2700);
WIRE 16 -1 (-5675 2700)(-7100 2700);
WIRE 16 -1 (-7800 2700)(-7100 2700);
FORCEPROP 2 LAST SIG_NAME VSENSE_VSS_SENSE_A_P1
J 2
(-7310 2710);
DISPLAY 0.489362 (-7310 2710);
WIRE 16 -1 (-7100 2625)(-7100 2700);
WIRE 16 -1 (-7800 2950)(-7100 2950);
FORCEPROP 2 LAST SIG_NAME VSENSE_PVDDCR_SOC_P1_DP
J 2
(-7260 2960);
DISPLAY 0.489362 (-7260 2960);
WIRE 16 -1 (-6050 2950)(-7100 2950);
WIRE 16 -1 (-7100 3025)(-7100 2950);
WIRE 16 -1 (-5750 3825)(-5750 3800);
WIRE 16 -1 (-5000 3800)(-5750 3800);
WIRE 16 -1 (-5750 3800)(-7100 3800);
WIRE 16 -1 (-7800 3800)(-7100 3800);
FORCEPROP 2 LAST SIG_NAME VSENSE_VSS_SENSE_A_P1
J 2
(-7310 3810);
DISPLAY 0.489362 (-7310 3810);
WIRE 16 -1 (-7100 3725)(-7100 3800);
WIRE 16 -1 (-7800 4050)(-7100 4050);
FORCEPROP 2 LAST SIG_NAME VSENSE_PVDDCR_CPU0_P1_DP
J 2
(-7235 4060);
DISPLAY 0.489362 (-7235 4060);
WIRE 16 -1 (-7100 4150)(-7100 4050);
WIRE 16 -1 (-6125 4050)(-7100 4050);
WIRE 16 -1 (-3650 2400)(-2825 2400);
FORCEPROP 2 LAST SIG_NAME PVDDCR_SOC_P1_PWM3
J 2
(-3060 2410);
DISPLAY 0.489362 (-3060 2410);
WIRE 16 -1 (-3650 2300)(-2825 2300);
FORCEPROP 2 LAST SIG_NAME PVDDCR_SOC_P1_IMON3
J 2
(-3035 2310);
DISPLAY 0.489362 (-3035 2310);
WIRE 17 273 (-1675 6575)(-1675 5275);
WIRE 17 273 (-1675 6575)(-75 6575);
WIRE 17 273 (-1675 5275)(-75 5275);
WIRE 17 273 (-75 6575)(-75 5275);
WIRE 16 -1 (-2050 6325)(-2050 6275);
WIRE 16 -1 (-2050 6275)(-2375 6275);
WIRE 16 -1 (-3650 6100)(-3375 6100);
WIRE 16 -1 (-3375 6100)(-3375 6275);
WIRE 16 -1 (-3375 6275)(-3250 6275);
WIRE 16 -1 (-3250 6275)(-2900 6275);
FORCEPROP 2 LAST SIG_NAME PVDDCR_CPU0_P1_VCC
J 2
(-2935 6285);
DISPLAY 0.489362 (-2935 6285);
FORCEPROP 2 LASTPROP $XRERR UNIQUE?
J 0
(-3175 6285);
DISPLAY 0.638298 (-3175 6285);
PAINT MONO (-3175 6285);
DISPLAY INVISIBLE (-3175 6285);
WIRE 16 -1 (-3250 6275)(-3250 6225);
WIRE 16 -1 (-2575 6275)(-2900 6275);
WIRE 16 -1 (-2900 6225)(-2900 6275);
WIRE 16 -1 (-3650 4500)(-2825 4500);
FORCEPROP 2 LAST SIG_NAME PVDDCR_CPU0_P1_PWM3
J 2
(-3010 4510);
DISPLAY 0.489362 (-3010 4510);
WIRE 16 -1 (-3650 4700)(-2825 4700);
FORCEPROP 2 LAST SIG_NAME PVDDCR_CPU0_P1_IMON2
J 2
(-3010 4710);
DISPLAY 0.489362 (-3010 4710);
WIRE 16 -1 (-3650 4800)(-2825 4800);
FORCEPROP 2 LAST SIG_NAME PVDDCR_CPU0_P1_PWM2
J 2
(-3035 4810);
DISPLAY 0.489362 (-3035 4810);
WIRE 16 -1 (-3650 5000)(-2850 5000);
FORCEPROP 2 LAST SIG_NAME PVDDCR_CPU0_P1_IMON1
J 2
(-3010 5010);
DISPLAY 0.489362 (-3010 5010);
WIRE 16 -1 (-3650 5100)(-2850 5100);
FORCEPROP 2 LAST SIG_NAME PVDDCR_CPU0_P1_PWM1
J 2
(-3035 5110);
DISPLAY 0.489362 (-3035 5110);
WIRE 16 -1 (-2925 5800)(-3250 5800);
WIRE 16 -1 (-2925 5800)(-2525 5800);
FORCEPROP 2 LAST SIG_NAME PVDDCR_CPU0_P1_VCCS
J 2
(-2535 5810);
DISPLAY 0.489362 (-2535 5810);
WIRE 16 -1 (-2925 5750)(-2925 5800);
WIRE 16 -1 (-3250 5800)(-3250 5750);
WIRE 16 -1 (-3250 5800)(-3650 5800);
WIRE 16 -1 (-2500 3125)(-2500 3200);
WIRE 16 -1 (-2500 3200)(-2725 3200);
WIRE 16 -1 (-2500 2525)(-2500 2600);
WIRE 16 -1 (-2500 2600)(-2725 2600);
WIRE 16 -1 (-3650 3500)(-2850 3500);
FORCEPROP 2 LAST SIG_NAME PVDDCR_CPU0_P1_IMON6
J 2
(-3010 3510);
DISPLAY 0.489362 (-3010 3510);
WIRE 16 -1 (-3650 2100)(-2825 2100);
FORCEPROP 2 LAST SIG_NAME PVDDCR_SOC_P1_PWM2
J 2
(-3060 2110);
DISPLAY 0.489362 (-3060 2110);
WIRE 16 -1 (-3650 2700)(-2925 2700);
FORCEPROP 2 LAST SIG_NAME NC_PVDDCR_CPU0_P1_PWM9
J 2
(-3010 2710);
DISPLAY 0.489362 (-3010 2710);
FORCEPROP 2 LASTPROP $XRERR UNIQUE?
J 0
(-2895 2700);
DISPLAY 0.638298 (-2895 2700);
PAINT MONO (-2895 2700);
DISPLAY INVISIBLE (-2895 2700);
WIRE 16 -1 (-3650 3200)(-2925 3200);
FORCEPROP 2 LAST SIG_NAME NC_PVDDCR_CPU0_P1_IMON7
J 2
(-2985 3210);
DISPLAY 0.489362 (-2985 3210);
FORCEPROP 2 LASTPROP $XRERR UNIQUE?
J 0
(-3225 3210);
DISPLAY 0.638298 (-3225 3210);
PAINT MONO (-3225 3210);
DISPLAY INVISIBLE (-3225 3210);
WIRE 16 -1 (-3650 3000)(-2925 3000);
FORCEPROP 2 LAST SIG_NAME NC_PVDDCR_CPU0_P1_PWM8
J 2
(-3010 3010);
DISPLAY 0.489362 (-3010 3010);
FORCEPROP 2 LASTPROP $XRERR UNIQUE?
J 0
(-2895 3000);
DISPLAY 0.638298 (-2895 3000);
PAINT MONO (-2895 3000);
DISPLAY INVISIBLE (-2895 3000);
WIRE 16 -1 (-3650 2900)(-2925 2900);
FORCEPROP 2 LAST SIG_NAME NC_PVDDCR_CPU0_P1_IMON8
J 2
(-2985 2910);
DISPLAY 0.489362 (-2985 2910);
FORCEPROP 2 LASTPROP $XRERR UNIQUE?
J 0
(-3225 2910);
DISPLAY 0.638298 (-3225 2910);
PAINT MONO (-3225 2910);
DISPLAY INVISIBLE (-3225 2910);
WIRE 16 -1 (-3650 2600)(-2925 2600);
FORCEPROP 2 LAST SIG_NAME NC_PVDDCR_CPU0_P1_IMON9
J 2
(-2985 2610);
DISPLAY 0.489362 (-2985 2610);
FORCEPROP 2 LASTPROP $XRERR UNIQUE?
J 0
(-3225 2610);
DISPLAY 0.638298 (-3225 2610);
PAINT MONO (-3225 2610);
DISPLAY INVISIBLE (-3225 2610);
WIRE 16 -1 (-2750 1200)(-2525 1200);
WIRE 16 -1 (-2750 1125)(-2750 1200);
WIRE 16 -1 (-2750 1200)(-3650 1200);
FORCEPROP 2 LAST SIG_NAME PVDDCR_SOC_P1_TEMP1
J 2
(-3060 1210);
DISPLAY 0.489362 (-3060 1210);
WIRE 16 -1 (-3650 1700)(-2850 1700);
FORCEPROP 2 LAST SIG_NAME PVDDCR_SOC_P1_IMON1
J 2
(-3035 1710);
DISPLAY 0.489362 (-3035 1710);
WIRE 16 -1 (-3650 1800)(-2850 1800);
FORCEPROP 2 LAST SIG_NAME PVDDCR_SOC_P1_PWM1
J 2
(-3060 1810);
DISPLAY 0.489362 (-3060 1810);
WIRE 16 -1 (-3650 2000)(-2825 2000);
FORCEPROP 2 LAST SIG_NAME PVDDCR_SOC_P1_IMON2
J 2
(-3035 2010);
DISPLAY 0.489362 (-3035 2010);
WIRE 16 -1 (-3100 900)(-3375 900);
FORCEPROP 2 LAST SIG_NAME PVDDCR_CPU0_P1_TEMP0
J 2
(-3110 910);
DISPLAY 0.489362 (-3110 910);
WIRE 16 -1 (-3375 800)(-3375 900);
WIRE 16 -1 (-3375 900)(-3650 900);
WIRE 16 -1 (-5000 6350)(-5000 6375);
WIRE 16 -1 (-5000 6375)(-5150 6375);
WIRE 16 -1 (-5650 6375)(-5650 6100);
WIRE 16 -1 (-5650 6375)(-5350 6375);
WIRE 16 -1 (-6025 6375)(-5650 6375);
WIRE 16 -1 (-5000 6100)(-5650 6100);
FORCEPROP 2 LAST SIG_NAME PWRGD_PVDDCR_CPU0_P1_R
J 2
(-5110 6110);
DISPLAY 0.489362 (-5110 6110);
FORCEPROP 2 LASTPROP $XRERR UNIQUE?
J 0
(-5350 6110);
DISPLAY 0.638298 (-5350 6110);
PAINT MONO (-5350 6110);
DISPLAY INVISIBLE (-5350 6110);
WIRE 16 -1 (-5650 6100)(-5800 6100);
WIRE 16 -1 (-5000 5800)(-5000 5825);
WIRE 16 -1 (-5000 5825)(-5125 5825);
WIRE 16 -1 (-5825 4950)(-5000 4950);
FORCEPROP 2 LAST SIG_NAME PVDDCR_CPU0_P1_PMSCL_R
J 2
(-5135 4960);
DISPLAY 0.489362 (-5135 4960);
FORCEPROP 2 LASTPROP $XRERR UNIQUE?
J 0
(-5375 4960);
DISPLAY 0.638298 (-5375 4960);
PAINT MONO (-5375 4960);
DISPLAY INVISIBLE (-5375 4960);
WIRE 16 -1 (-5000 5200)(-5925 5200);
FORCEPROP 2 LAST SIG_NAME SVID_PVDDCR_CPU0_P1_SVTI_R
J 0
(-5710 5210);
DISPLAY 0.489362 (-5710 5210);
FORCEPROP 2 LASTPROP $XRERR UNIQUE?
J 0
(-5950 5210);
DISPLAY 0.638298 (-5950 5210);
PAINT MONO (-5950 5210);
DISPLAY INVISIBLE (-5950 5210);
WIRE 16 -1 (-5000 5350)(-5925 5350);
FORCEPROP 2 LAST SIG_NAME SVID_PVDDCR_CPU0_P1_SVTO_R
J 0
(-5710 5360);
DISPLAY 0.489362 (-5710 5360);
FORCEPROP 2 LASTPROP $XRERR UNIQUE?
J 0
(-5950 5360);
DISPLAY 0.638298 (-5950 5360);
PAINT MONO (-5950 5360);
DISPLAY INVISIBLE (-5950 5360);
WIRE 16 -1 (-5825 4650)(-5000 4650);
FORCEPROP 2 LAST SIG_NAME PVDDCR_CPU0_P1_PMALERT_R
J 2
(-5085 4660);
DISPLAY 0.489362 (-5085 4660);
FORCEPROP 2 LASTPROP $XRERR UNIQUE?
J 0
(-5325 4660);
DISPLAY 0.638298 (-5325 4660);
PAINT MONO (-5325 4660);
DISPLAY INVISIBLE (-5325 4660);
WIRE 16 -1 (-5325 5825)(-5625 5825);
WIRE 16 -1 (-5625 5825)(-5625 5950);
WIRE 16 -1 (-5625 5950)(-5000 5950);
FORCEPROP 2 LAST SIG_NAME PVDDCR_CPU0_P1_EN_R
J 2
(-5110 5960);
DISPLAY 0.489362 (-5110 5960);
FORCEPROP 2 LASTPROP $XRERR UNIQUE?
J 0
(-5350 5960);
DISPLAY 0.638298 (-5350 5960);
PAINT MONO (-5350 5960);
DISPLAY INVISIBLE (-5350 5960);
WIRE 16 -1 (-5800 5950)(-5625 5950);
WIRE 16 -1 (-6025 4650)(-6700 4650);
FORCEPROP 2 LAST SIG_NAME PVDDCR_CPU0_P1_PMALERT
J 0
(-6700 4660);
DISPLAY 0.489362 (-6700 4660);
WIRE 16 -1 (-6700 4800)(-6025 4800);
FORCEPROP 2 LAST SIG_NAME SMB_SCM_6_R2_SDA
J 0
(-6700 4810);
DISPLAY 0.489362 (-6700 4810);
WIRE 16 -1 (-6700 4950)(-6025 4950);
FORCEPROP 2 LAST SIG_NAME SMB_SCM_6_R2_SCL
J 0
(-6700 4960);
DISPLAY 0.489362 (-6700 4960);
WIRE 16 -1 (-6000 6100)(-6575 6100);
FORCEPROP 2 LAST SIG_NAME PWRGD_PVDDCR_CPU0_P1
J 2
(-6110 6110);
DISPLAY 0.489362 (-6110 6110);
WIRE 16 -1 (-6000 5950)(-6575 5950);
FORCEPROP 2 LAST SIG_NAME PVDDCR_CPU0_P1_EN
J 2
(-6185 5960);
DISPLAY 0.489362 (-6185 5960);
WIRE 16 -1 (-6525 6450)(-6525 6375);
WIRE 16 -1 (-6525 6375)(-6225 6375);
WIRE 16 -1 (-7425 5650)(-7550 5650);
WIRE 16 -1 (-5000 5650)(-7425 5650);
FORCEPROP 2 LAST SIG_NAME SVID_PVDDCR_CPU0_P1_SVC_R
J 0
(-5685 5660);
DISPLAY 0.489362 (-5685 5660);
WIRE 16 -1 (-7425 5875)(-7425 5650);
WIRE 16 -1 (-7550 5125)(-7550 5650);
WIRE 16 -1 (-7550 5650)(-8850 5650);
WIRE 16 -1 (-8850 5500)(-7825 5500);
WIRE 16 -1 (-7700 5500)(-7825 5500);
WIRE 16 -1 (-7825 5125)(-7825 5500);
WIRE 16 -1 (-7700 5500)(-5000 5500);
FORCEPROP 2 LAST SIG_NAME SVID_PVDDCR_CPU0_P1_SVD_R
J 0
(-5685 5510);
DISPLAY 0.489362 (-5685 5510);
WIRE 16 -1 (-7700 5875)(-7700 5500);
WIRE 16 -1 (-5925 4050)(-5750 4050);
WIRE 16 -1 (-5000 4050)(-5750 4050);
FORCEPROP 2 LAST SIG_NAME VSENSE_PVDDCR_CPU0_P1_VSEN0
J 2
(-5110 4060);
DISPLAY 0.489362 (-5110 4060);
FORCEPROP 2 LASTPROP $XRERR UNIQUE?
J 0
(-5350 4060);
DISPLAY 0.638298 (-5350 4060);
PAINT MONO (-5350 4060);
DISPLAY INVISIBLE (-5350 4060);
WIRE 16 -1 (-5750 4025)(-5750 4050);
WIRE 16 -1 (-5850 2950)(-5675 2950);
WIRE 16 -1 (-5675 2950)(-5000 2950);
FORCEPROP 2 LAST SIG_NAME VSENSE_PVDDCR_SOC_P1_VSEN1
J 2
(-5110 2960);
DISPLAY 0.489362 (-5110 2960);
FORCEPROP 2 LASTPROP $XRERR UNIQUE?
J 0
(-5350 2960);
DISPLAY 0.638298 (-5350 2960);
PAINT MONO (-5350 2960);
DISPLAY INVISIBLE (-5350 2960);
WIRE 16 -1 (-5675 2925)(-5675 2950);
WIRE 16 -1 (-5975 2400)(-5875 2400);
WIRE 16 -1 (-5875 2400)(-5875 2250);
WIRE 16 -1 (-5000 2250)(-5875 2250);
FORCEPROP 2 LAST SIG_NAME PVDDCR_CPU0_P1_RESET_N_R
J 0
(-5710 2260);
DISPLAY 0.489362 (-5710 2260);
FORCEPROP 2 LASTPROP $XRERR UNIQUE?
J 0
(-5950 2260);
DISPLAY 0.638298 (-5950 2260);
PAINT MONO (-5950 2260);
DISPLAY INVISIBLE (-5950 2260);
WIRE 16 -1 (-5950 2250)(-5875 2250);
WIRE 16 -1 (-5300 1975)(-5150 1975);
WIRE 16 -1 (-5150 1975)(-5150 2100);
WIRE 16 -1 (-5000 2100)(-5150 2100);
WIRE 16 -1 (-5950 2100)(-5150 2100);
FORCEPROP 2 LAST SIG_NAME PVDDCR_CPU0_P1_OCP_N_R
J 0
(-5685 2110);
DISPLAY 0.489362 (-5685 2110);
FORCEPROP 2 LASTPROP $XRERR UNIQUE?
J 0
(-5925 2110);
DISPLAY 0.638298 (-5925 2110);
PAINT MONO (-5925 2110);
DISPLAY INVISIBLE (-5925 2110);
WIRE 16 -1 (-5100 500)(-5100 550);
WIRE 16 -1 (-5100 550)(-5000 550);
WIRE 16 -1 (-5325 1175)(-5325 1250);
WIRE 16 -1 (-5325 1250)(-5550 1250);
WIRE 16 -1 (-6075 1725)(-6225 1725);
WIRE 16 -1 (-5775 1725)(-6075 1725);
WIRE 16 -1 (-6075 1725)(-6075 1850);
WIRE 16 -1 (-6225 1725)(-6225 1750);
WIRE 16 -1 (-5000 1850)(-6075 1850);
WIRE 16 -1 (-6075 1975)(-6075 1850);
WIRE 16 -1 (-5500 1975)(-6075 1975);
WIRE 16 -1 (-6200 675)(-6200 650);
WIRE 16 -1 (-6200 650)(-6050 650);
WIRE 16 -1 (-7100 1500)(-5825 1500);
WIRE 16 -1 (-7100 1550)(-7100 1500);
WIRE 16 -1 (-7100 1500)(-7100 1475);
WIRE 16 -1 (-5825 1500)(-5825 1350);
WIRE 16 -1 (-5825 1350)(-5000 1350);
FORCEPROP 2 LAST SIG_NAME PVDDCR_SOC_P1_EN//ADDR_CFG
J 2
(-5110 1360);
DISPLAY 0.489362 (-5110 1360);
FORCEPROP 2 LASTPROP $XRERR UNIQUE?
J 0
(-5350 1360);
DISPLAY 0.638298 (-5350 1360);
PAINT MONO (-5350 1360);
DISPLAY INVISIBLE (-5350 1360);
WIRE 16 -1 (-6525 2475)(-6525 2400);
WIRE 16 -1 (-6525 2400)(-6175 2400);
WIRE 16 -1 (-6675 2250)(-6150 2250);
FORCEPROP 2 LAST SIG_NAME PVDDCR_CPU0_P1_RESET_N
J 0
(-6660 2260);
DISPLAY 0.489362 (-6660 2260);
WIRE 16 -1 (-6675 2100)(-6150 2100);
FORCEPROP 2 LAST SIG_NAME PVDDCR_CPU0_P1_OCP_N
J 0
(-6660 2110);
DISPLAY 0.489362 (-6660 2110);
WIRE 16 -1 (-7100 2225)(-7775 2225);
WIRE 16 -1 (-7100 2150)(-7100 2225);
WIRE 16 -1 (-7775 2225)(-7775 2250);
WIRE 16 -1 (-7775 2175)(-7775 2225);
WIRE 17 273 (-8050 3200)(-8050 2390);
WIRE 17 273 (-8050 3200)(-7200 3200);
WIRE 17 273 (-8050 2390)(-7200 2390);
WIRE 17 273 (-7200 3200)(-7200 2390);
WIRE 16 -1 (-6600 1350)(-6600 1250);
WIRE 16 -1 (-6600 1250)(-6425 1250);
WIRE 16 -1 (-7775 1250)(-7100 1250);
WIRE 16 -1 (-7775 1250)(-7775 1325);
WIRE 16 -1 (-7100 1225)(-7100 1250);
WIRE 16 -1 (-7100 1275)(-7100 1250);
WIRE 16 -1 (-7775 1625)(-7775 1850);
WIRE 16 -1 (-7400 1850)(-7775 1850);
FORCEPROP 2 LAST SIG_NAME PVDDCR_SOC_P1_EN_GD
J 2
(-7310 1800);
DISPLAY 0.489362 (-7310 1800);
FORCEPROP 2 LASTPROP $XRERR UNIQUE?
J 0
(-7550 1800);
DISPLAY 0.638298 (-7550 1800);
PAINT MONO (-7550 1800);
DISPLAY INVISIBLE (-7550 1800);
WIRE 16 -1 (-7775 1975)(-7775 1850);
WIRE 16 -1 (-7925 1425)(-8175 1425);
FORCEPROP 2 LAST SIG_NAME PVDDCR_SOC_P1_EN_RC
J 2
(-7960 1435);
DISPLAY 0.489362 (-7960 1435);
FORCEPROP 2 LASTPROP $XRERR UNIQUE?
J 0
(-8200 1435);
DISPLAY 0.638298 (-8200 1435);
PAINT MONO (-8200 1435);
DISPLAY INVISIBLE (-8200 1435);
WIRE 16 -1 (-8175 1325)(-8175 1425);
WIRE 16 -1 (-8175 1425)(-8500 1425);
WIRE 16 -1 (-7550 900)(-7550 825);
WIRE 16 -1 (-7550 825)(-7350 825);
WIRE 16 -1 (-8350 6075)(-8350 6175);
WIRE 16 -1 (-8000 6175)(-8350 6175);
WIRE 16 -1 (-8350 6225)(-8350 6175);
WIRE 16 -1 (-7700 6175)(-8000 6175);
WIRE 16 -1 (-8000 6075)(-8000 6175);
WIRE 16 -1 (-7700 6075)(-7700 6175);
WIRE 16 -1 (-7425 6175)(-7700 6175);
WIRE 16 -1 (-7425 6175)(-7425 6075);
WIRE 16 -1 (-8850 5350)(-8250 5350);
WIRE 16 -1 (-8050 5350)(-8250 5350);
WIRE 16 -1 (-8250 5350)(-8250 5125);
WIRE 16 -1 (-8000 5350)(-8050 5350);
WIRE 16 -1 (-8050 5125)(-8050 5350);
WIRE 16 -1 (-6125 5350)(-8000 5350);
FORCEPROP 2 LAST SIG_NAME SVID_PVDDCR_CPU0_P1_SVTO
J 0
(-7085 5360);
DISPLAY 0.489362 (-7085 5360);
WIRE 16 -1 (-8000 5875)(-8000 5350);
WIRE 16 -1 (-8525 5200)(-8350 5200);
WIRE 16 -1 (-8525 5200)(-8525 5125);
WIRE 16 -1 (-6125 5200)(-8350 5200);
FORCEPROP 2 LAST SIG_NAME SVID_PVDDCR_CPU0_P1_SVTI
J 0
(-7085 5225);
DISPLAY 0.489362 (-7085 5225);
FORCEPROP 2 LASTPROP $XRERR UNIQUE?
J 0
(-7325 5225);
DISPLAY 0.638298 (-7325 5225);
PAINT MONO (-7325 5225);
DISPLAY INVISIBLE (-7325 5225);
WIRE 16 -1 (-8350 5875)(-8350 5200);
WIRE 16 -1 (-8700 1425)(-9125 1425);
FORCEPROP 2 LAST SIG_NAME PVDDCR_SOC_P1_EN
J 2
(-8785 1435);
DISPLAY 0.489362 (-8785 1435);
WIRE 17 273 (-8050 4275)(-8050 3465);
WIRE 17 273 (-8050 4275)(-7200 4275);
WIRE 17 273 (-8050 3465)(-7200 3465);
WIRE 17 273 (-7200 4275)(-7200 3465);
WIRE 16 -1 (-5850 650)(-5625 650);
WIRE 16 -1 (-5625 650)(-5300 650);
WIRE 16 -1 (-5625 550)(-5625 650);
WIRE 16 -1 (-5000 650)(-5300 650);
FORCEPROP 2 LAST SIG_NAME PVDDCR_CPU0_P1_VINSEN
J 2
(-5110 660);
DISPLAY 0.489362 (-5110 660);
FORCEPROP 2 LASTPROP $XRERR UNIQUE?
J 0
(-5350 660);
DISPLAY 0.638298 (-5350 660);
PAINT MONO (-5350 660);
DISPLAY INVISIBLE (-5350 660);
WIRE 16 -1 (-5300 575)(-5300 650);
WIRE 16 -1 (-6425 1000)(-7100 1000);
FORCEPROP 2 LAST SIG_NAME PWRGD_PVDDCR_SOC_P1
J 2
(-6560 1010);
DISPLAY 0.489362 (-6560 1010);
WIRE 16 -1 (-3650 3800)(-2850 3800);
FORCEPROP 2 LAST SIG_NAME PVDDCR_CPU0_P1_IMON5
J 2
(-3010 3810);
DISPLAY 0.489362 (-3010 3810);
WIRE 16 -1 (-3650 4100)(-2850 4100);
FORCEPROP 2 LAST SIG_NAME PVDDCR_CPU0_P1_IMON4
J 2
(-3010 4110);
DISPLAY 0.489362 (-3010 4110);
WIRE 16 -1 (-5825 4800)(-5000 4800);
FORCEPROP 2 LAST SIG_NAME PVDDCR_CPU0_P1_PMSDA_R
J 2
(-5135 4810);
DISPLAY 0.489362 (-5135 4810);
FORCEPROP 2 LASTPROP $XRERR UNIQUE?
J 0
(-5375 4810);
DISPLAY 0.638298 (-5375 4810);
PAINT MONO (-5375 4810);
DISPLAY INVISIBLE (-5375 4810);
WIRE 17 273 (-1675 5200)(-1675 4025);
WIRE 17 273 (-1675 5200)(-75 5200);
WIRE 17 273 (-1675 4025)(-75 4025);
WIRE 17 273 (-75 5200)(-75 4025);
WIRE 16 -1 (-3650 3900)(-2850 3900);
FORCEPROP 2 LAST SIG_NAME PVDDCR_CPU0_P1_PWM5
J 2
(-3035 3910);
DISPLAY 0.489362 (-3035 3910);
WIRE 16 -1 (-3650 4200)(-2850 4200);
FORCEPROP 2 LAST SIG_NAME PVDDCR_CPU0_P1_PWM4
J 2
(-3035 4210);
DISPLAY 0.489362 (-3035 4210);
WIRE 16 -1 (-3650 4400)(-2825 4400);
FORCEPROP 2 LAST SIG_NAME PVDDCR_CPU0_P1_IMON3
J 2
(-2985 4410);
DISPLAY 0.489362 (-2985 4410);
WIRE 16 -1 (-3650 3600)(-2850 3600);
FORCEPROP 2 LAST SIG_NAME PVDDCR_CPU0_P1_PWM6
J 2
(-3035 3610);
DISPLAY 0.489362 (-3035 3610);
WIRE 16 -1 (-3650 3300)(-2925 3300);
FORCEPROP 2 LAST SIG_NAME NC_PVDDCR_CPU0_P1_PWM7
J 2
(-3010 3310);
DISPLAY 0.489362 (-3010 3310);
FORCEPROP 2 LASTPROP $XRERR UNIQUE?
J 0
(-2895 3300);
DISPLAY 0.638298 (-2895 3300);
PAINT MONO (-2895 3300);
DISPLAY INVISIBLE (-2895 3300);
WIRE 16 -1 (-2500 2825)(-2500 2900);
WIRE 16 -1 (-2500 2900)(-2725 2900);
WIRE 16 -1 (-6225 1250)(-6050 1250);
WIRE 16 -1 (-6050 1250)(-5750 1250);
WIRE 16 -1 (-6050 1250)(-6050 1000);
WIRE 16 -1 (-6050 1000)(-5325 1000);
FORCEPROP 2 LAST SIG_NAME PWRGD_PVDDCR_SOC_P1_R
J 2
(-5485 1010);
DISPLAY 0.489362 (-5485 1010);
FORCEPROP 2 LASTPROP $XRERR UNIQUE?
J 0
(-5725 1010);
DISPLAY 0.638298 (-5725 1010);
PAINT MONO (-5725 1010);
DISPLAY INVISIBLE (-5725 1010);
WIRE 16 -1 (-6050 1000)(-6225 1000);
WIRE 16 -1 (-5325 850)(-5325 1000);
WIRE 16 -1 (-5000 850)(-5325 850);
WIRE 16 -1 (-5625 750)(-5000 750);
FORCEPROP 2 LAST SIG_NAME PVDDCR_CPU0_P1_VMON
J 2
(-5135 760);
DISPLAY 0.489362 (-5135 760);
FORCEPROP 2 LASTPROP $XRERR UNIQUE?
J 0
(-5375 760);
DISPLAY 0.638298 (-5375 760);
PAINT MONO (-5375 760);
DISPLAY INVISIBLE (-5375 760);
WIRE 16 -1 (-5625 825)(-5625 750);
WIRE 16 -1 (-5625 825)(-6475 825);
WIRE 16 -1 (-6475 750)(-6475 825);
WIRE 16 -1 (-6950 825)(-6475 825);
WIRE 16 -1 (-7150 825)(-6950 825);
WIRE 16 -1 (-6950 750)(-6950 825);
WIRE 17 273 (-9175 600)(-7975 600);
WIRE 17 273 (-9175 600)(-9175 200);
WIRE 17 273 (-7975 600)(-7975 200);
WIRE 17 273 (-9175 200)(-7975 200);
DOT 1 (-5150 2100);
DOT 1 (-8350 5200);
DOT 1 (-8250 5350);
DOT 1 (-8350 6175);
DOT 1 (-8175 1425);
DOT 1 (-7775 1850);
DOT 1 (-6950 825);
DOT 1 (-6475 825);
DOT 1 (-7100 1250);
DOT 1 (-7100 1500);
DOT 1 (-7775 2225);
DOT 1 (-7100 2700);
DOT 1 (-7100 2950);
DOT 1 (-7100 3800);
DOT 1 (-7100 4050);
DOT 1 (-6050 1000);
DOT 1 (-6050 1250);
DOT 1 (-6075 1725);
DOT 1 (-6075 1850);
DOT 1 (-5875 2250);
DOT 1 (-5675 2700);
DOT 1 (-5675 2950);
DOT 1 (-5750 3800);
DOT 1 (-5750 4050);
DOT 1 (-8050 5350);
DOT 1 (-8000 5350);
DOT 1 (-7825 5500);
DOT 1 (-7550 5650);
DOT 1 (-8000 6175);
DOT 1 (-7700 6175);
DOT 1 (-5650 6100);
DOT 1 (-5625 5950);
DOT 1 (-5650 6375);
DOT 1 (-3375 900);
DOT 1 (-2750 1200);
DOT 1 (-3250 5800);
DOT 1 (-2925 5800);
DOT 1 (-3250 6275);
DOT 1 (-2900 6275);
DOT 1 (-7425 5650);
DOT 1 (-7700 5500);
DOT 1 (-5300 650);
DOT 1 (-5625 650);
FORCENOTE
VR
(-9100 525) 0;
DISPLAY LEFT (-9100 525);
DISPLAY 0.808511 (-9100 525);
PAINT WHITE (-9100 525);
FORCENOTE
RENESAS
(-9100 425) 0;
DISPLAY LEFT (-9100 425);
DISPLAY 0.638298 (-9100 425);
PAINT WHITE (-9100 425);
FORCENOTE
INFINEON
(-9100 350) 0;
DISPLAY LEFT (-9100 350);
DISPLAY 0.638298 (-9100 350);
PAINT WHITE (-9100 350);
FORCENOTE
0X4D
(-8650 275) 0;
DISPLAY LEFT (-8650 275);
DISPLAY 0.638298 (-8650 275);
PAINT WHITE (-8650 275);
FORCENOTE
PMBUS ADDRESS AND CONFIG
(-9200 650) 0;
DISPLAY LEFT (-9200 650);
DISPLAY 1.170213 (-9200 650);
PAINT WHITE (-9200 650);
FORCENOTE
ADDRESS
(-8650 525) 0;
DISPLAY LEFT (-8650 525);
DISPLAY 0.808511 (-8650 525);
PAINT WHITE (-8650 525);
FORCENOTE
2/6.65K
(-8300 425) 0;
DISPLAY LEFT (-8300 425);
DISPLAY 0.638298 (-8300 425);
PAINT WHITE (-8300 425);
FORCENOTE
/52.3K
(-8300 275) 0;
DISPLAY LEFT (-8300 275);
DISPLAY 0.638298 (-8300 275);
PAINT WHITE (-8300 275);
FORCENOTE
0X72
(-8650 425) 0;
DISPLAY LEFT (-8650 425);
DISPLAY 0.638298 (-8650 425);
PAINT WHITE (-8650 425);
FORCENOTE
/1.47K
(-8300 350) 0;
DISPLAY LEFT (-8300 350);
DISPLAY 0.638298 (-8300 350);
PAINT WHITE (-8300 350);
FORCENOTE
0X4D
(-8650 350) 0;
DISPLAY LEFT (-8650 350);
DISPLAY 0.638298 (-8650 350);
PAINT WHITE (-8650 350);
FORCENOTE
MPS
(-9100 275) 0;
DISPLAY LEFT (-9100 275);
DISPLAY 0.638298 (-9100 275);
PAINT WHITE (-9100 275);
FORCENOTE
CONFIG/R
(-8300 525) 0;
DISPLAY LEFT (-8300 525);
DISPLAY 0.808511 (-8300 525);
PAINT WHITE (-8300 525);
FORCENOTE
BOM NOTE
(-1725 3200) 0;
DISPLAY LEFT (-1725 3200);
DISPLAY 1.021277 (-1725 3200);
PAINT WHITE (-1725 3200);
FORCENOTE
WORK FREQUENCY=600KHZ
(-1650 4250) 0;
DISPLAY LEFT (-1650 4250);
DISPLAY 0.936170 (-1650 4250);
PAINT WHITE (-1650 4250);
FORCENOTE
LOAD RELEASE=95A
(-1650 4325) 0;
DISPLAY LEFT (-1650 4325);
DISPLAY 0.936170 (-1650 4325);
PAINT WHITE (-1650 4325);
FORCENOTE
DIFFERENTIAL PAIR
(-8000 3675) 0;
DISPLAY LEFT (-8000 3675);
DISPLAY 0.808511 (-8000 3675);
PAINT WHITE (-8000 3675);
FORCENOTE
TRACE WIDTH = 10MIL
(-7975 2500) 0;
DISPLAY LEFT (-7975 2500);
DISPLAY 0.808511 (-7975 2500);
PAINT WHITE (-7975 2500);
FORCENOTE
DIFFERENTIAL PAIR
(-7975 2575) 0;
DISPLAY LEFT (-7975 2575);
DISPLAY 0.808511 (-7975 2575);
PAINT WHITE (-7975 2575);
FORCENOTE
TRACE SPACING = 5MIL
(-7975 2425) 0;
DISPLAY LEFT (-7975 2425);
DISPLAY 0.808511 (-7975 2425);
PAINT WHITE (-7975 2425);
FORCENOTE
LOAD STEP=45A
(-1650 4400) 0;
DISPLAY LEFT (-1650 4400);
DISPLAY 0.936170 (-1650 4400);
PAINT WHITE (-1650 4400);
FORCENOTE
VID=0.75-1.2V
(-1650 5000) 0;
DISPLAY LEFT (-1650 5000);
DISPLAY 0.936170 (-1650 5000);
PAINT WHITE (-1650 5000);
FORCENOTE
DC=+/-20MV
(-1650 4850) 0;
DISPLAY LEFT (-1650 4850);
DISPLAY 0.936170 (-1650 4850);
PAINT WHITE (-1650 4850);
FORCENOTE
TDC=105A
(-1650 4625) 0;
DISPLAY LEFT (-1650 4625);
DISPLAY 0.936170 (-1650 4625);
PAINT WHITE (-1650 4625);
FORCENOTE
EDC=130A
(-1650 4550) 0;
DISPLAY LEFT (-1650 4550);
DISPLAY 0.936170 (-1650 4550);
PAINT WHITE (-1650 4550);
FORCENOTE
RIPPLE=+/-10MV
(-1650 4925) 0;
DISPLAY LEFT (-1650 4925);
DISPLAY 0.936170 (-1650 4925);
PAINT WHITE (-1650 4925);
FORCENOTE
LOAD STEP=200A
(-1650 5750) 0;
DISPLAY LEFT (-1650 5750);
DISPLAY 0.936170 (-1650 5750);
PAINT WHITE (-1650 5750);
FORCENOTE
EDC=230A
(-1650 5900) 0;
DISPLAY LEFT (-1650 5900);
DISPLAY 0.936170 (-1650 5900);
PAINT WHITE (-1650 5900);
FORCENOTE
TDC=175A
(-1650 5975) 0;
DISPLAY LEFT (-1650 5975);
DISPLAY 0.936170 (-1650 5975);
PAINT WHITE (-1650 5975);
FORCENOTE
MIN AC=VID-EDC*LL-110MV
(-1650 6050) 0;
DISPLAY LEFT (-1650 6050);
DISPLAY 0.936170 (-1650 6050);
PAINT WHITE (-1650 6050);
FORCENOTE
SVI3 ADDRESS=PORT0 (0X1)
(-1650 5375) 0;
DISPLAY LEFT (-1650 5375);
DISPLAY 0.936170 (-1650 5375);
PAINT WHITE (-1650 5375);
FORCENOTE
OCP=276A (EDC*1.2)
(-1650 5825) 0;
DISPLAY LEFT (-1650 5825);
DISPLAY 0.936170 (-1650 5825);
PAINT WHITE (-1650 5825);
FORCENOTE
WORK FREQUENCY=600KHZ
(-1650 5525) 0;
DISPLAY LEFT (-1650 5525);
DISPLAY 0.936170 (-1650 5525);
PAINT WHITE (-1650 5525);
FORCENOTE
LOAD RELEASE=200A
(-1650 5675) 0;
DISPLAY LEFT (-1650 5675);
DISPLAY 0.936170 (-1650 5675);
PAINT WHITE (-1650 5675);
FORCENOTE
LOAD-LINE=0.4MOHM
(-1650 5600) 0;
DISPLAY LEFT (-1650 5600);
DISPLAY 0.936170 (-1650 5600);
PAINT WHITE (-1650 5600);
FORCENOTE
OCP=156A (EDC*1.2)
(-1650 4475) 0;
DISPLAY LEFT (-1650 4475);
DISPLAY 0.936170 (-1650 4475);
PAINT WHITE (-1650 4475);
FORCENOTE
MIN AC=VID-150MV
(-1650 4700) 0;
DISPLAY LEFT (-1650 4700);
DISPLAY 0.936170 (-1650 4700);
PAINT WHITE (-1650 4700);
FORCENOTE
MAX AC=VID+150MV
(-1650 4775) 0;
DISPLAY LEFT (-1650 4775);
DISPLAY 0.936170 (-1650 4775);
PAINT WHITE (-1650 4775);
FORCENOTE
MAX AC=+200MV
(-1650 6125) 0;
DISPLAY LEFT (-1650 6125);
DISPLAY 0.936170 (-1650 6125);
PAINT WHITE (-1650 6125);
FORCENOTE
PVDDCR_CPU0_P1 SPECFICATION
(-1650 6497) 0;
DISPLAY LEFT (-1650 6497);
DISPLAY 1.170213 (-1650 6497);
PAINT WHITE (-1650 6497);
FORCENOTE
VID=0.55-2V
(-1650 6350) 0;
DISPLAY LEFT (-1650 6350);
DISPLAY 0.936170 (-1650 6350);
PAINT WHITE (-1650 6350);
FORCENOTE
DC=+/-20MV
(-1650 6200) 0;
DISPLAY LEFT (-1650 6200);
DISPLAY 0.936170 (-1650 6200);
PAINT WHITE (-1650 6200);
FORCENOTE
RIPPLE=+/-10MV
(-1650 6275) 0;
DISPLAY LEFT (-1650 6275);
DISPLAY 0.936170 (-1650 6275);
PAINT WHITE (-1650 6275);
FORCENOTE
TRACE SPACING = 5MIL
(-8000 3525) 0;
DISPLAY LEFT (-8000 3525);
DISPLAY 0.808511 (-8000 3525);
PAINT WHITE (-8000 3525);
FORCENOTE
TRACE WIDTH = 10MIL
(-8000 3600) 0;
DISPLAY LEFT (-8000 3600);
DISPLAY 0.808511 (-8000 3600);
PAINT WHITE (-8000 3600);
FORCENOTE
EFFICIENCY > 90% @TDC
(-1650 5450) 0;
DISPLAY LEFT (-1650 5450);
DISPLAY 0.936170 (-1650 5450);
PAINT WHITE (-1650 5450);
FORCENOTE
PVDDCR_SOC_P1 SPECFICATION
(-1650 5125) 0;
DISPLAY LEFT (-1650 5125);
DISPLAY 1.276596 (-1650 5125);
PAINT WHITE (-1650 5125);
FORCENOTE
EFFICIENCY > 90% @TDC
(-1650 4175) 0;
DISPLAY LEFT (-1650 4175);
DISPLAY 0.936170 (-1650 4175);
PAINT WHITE (-1650 4175);
FORCENOTE
SVI3 ADDRESS=PORT0 (0X2)
(-1650 4100) 0;
DISPLAY LEFT (-1650 4100);
DISPLAY 0.936170 (-1650 4100);
PAINT WHITE (-1650 4100);
FORCENOTE
PU25=AR0T6GPV001
(-1725 2775) 0;
DISPLAY LEFT (-1725 2775);
DISPLAY 1.021277 (-1725 2775);
PAINT WHITE (-1725 2775);
FORCENOTE
MAIN SOURCE:RENESAS BOM
(-1725 3075) 0;
DISPLAY LEFT (-1725 3075);
DISPLAY 1.021277 (-1725 3075);
PAINT WHITE (-1725 3075);
FORCENOTE
PU25=AR0T6GPV005/RAA229620GNP#HA0
(-1725 3000) 0;
DISPLAY LEFT (-1725 3000);
DISPLAY 1.021277 (-1725 3000);
PAINT WHITE (-1725 3000);
FORCENOTE
2ND SOURCE:INFENEON BOM
(-1725 2850) 0;
DISPLAY LEFT (-1725 2850);
DISPLAY 1.021277 (-1725 2850);
PAINT WHITE (-1725 2850);
FORCENOTE
PR159=CS21472FB00
(-1725 2700) 0;
DISPLAY LEFT (-1725 2700);
DISPLAY 1.021277 (-1725 2700);
PAINT WHITE (-1725 2700);
FORCENOTE
PC251 = CH5103KEB01
(-1725 2625) 0;
DISPLAY LEFT (-1725 2625);
DISPLAY 1.021277 (-1725 2625);
PAINT WHITE (-1725 2625);
FORCENOTE
PC244,PC245 = CH12206KB14
(-1725 2475) 0;
DISPLAY LEFT (-1725 2475);
DISPLAY 1.021277 (-1725 2475);
PAINT WHITE (-1725 2475);
FORCENOTE
PR157 = CS25362FB15
(-1725 2400) 0;
DISPLAY LEFT (-1725 2400);
DISPLAY 1.021277 (-1725 2400);
PAINT WHITE (-1725 2400);
FORCENOTE
PC253,PC250 = CH11006JB00
(-1725 2550) 0;
DISPLAY LEFT (-1725 2550);
DISPLAY 1.021277 (-1725 2550);
PAINT WHITE (-1725 2550);
FORCENOTE
PR159=CS35232FB02
(-1725 1800) 0;
DISPLAY LEFT (-1725 1800);
DISPLAY 1.021277 (-1725 1800);
PAINT WHITE (-1725 1800);
FORCENOTE
PC244,PC245,PR157,PC243=EMPTY
(-1725 1725) 0;
DISPLAY LEFT (-1725 1725);
DISPLAY 1.021277 (-1725 1725);
PAINT WHITE (-1725 1725);
FORCENOTE
PR530,PR436,PR437=EMPTY
(-1725 1650) 0;
DISPLAY LEFT (-1725 1650);
DISPLAY 1.021277 (-1725 1650);
PAINT WHITE (-1725 1650);
FORCENOTE
PC250,PC253=TMP_QCH31004KB17
(-1725 1275) 0;
DISPLAY LEFT (-1725 1275);
DISPLAY 1.021277 (-1725 1275);
PAINT WHITE (-1725 1275);
FORCENOTE
PR4=CS00002JB38
(-1725 1575) 0;
DISPLAY LEFT (-1725 1575);
DISPLAY 1.021277 (-1725 1575);
PAINT WHITE (-1725 1575);
FORCENOTE
PR181=CS37502FB05
(-1725 1500) 0;
DISPLAY LEFT (-1725 1500);
DISPLAY 1.021277 (-1725 1500);
PAINT WHITE (-1725 1500);
FORCENOTE
PR602=CS24992FB07
(-1725 1425) 0;
DISPLAY LEFT (-1725 1425);
DISPLAY 1.021277 (-1725 1425);
PAINT WHITE (-1725 1425);
FORCENOTE
PC6=TMP_QCH21006JB10
(-1725 1350) 0;
DISPLAY LEFT (-1725 1350);
DISPLAY 1.021277 (-1725 1350);
PAINT WHITE (-1725 1350);
FORCENOTE
PU25=AL002857001
(-1725 1875) 0;
DISPLAY LEFT (-1725 1875);
DISPLAY 1.021277 (-1725 1875);
PAINT WHITE (-1725 1875);
FORCENOTE
3RD SOURCE:MPS BOM
(-1725 1950) 0;
DISPLAY LEFT (-1725 1950);
DISPLAY 1.021277 (-1725 1950);
PAINT WHITE (-1725 1950);
FORCENOTE
PR530,PR436,PR437 = EMPTY
(-1725 2250) 0;
DISPLAY LEFT (-1725 2250);
DISPLAY 1.021277 (-1725 2250);
PAINT WHITE (-1725 2250);
FORCENOTE
PR4 = CS21002FB24
(-1725 2325) 0;
DISPLAY LEFT (-1725 2325);
DISPLAY 1.021277 (-1725 2325);
PAINT WHITE (-1725 2325);
FORCENOTE
PR150 = CS00002JB38
(-1725 2175) 0;
DISPLAY LEFT (-1725 2175);
DISPLAY 1.021277 (-1725 2175);
PAINT WHITE (-1725 2175);
FORCENOTE
PC243 = CH3104J1B00
(-1725 2100) 0;
DISPLAY LEFT (-1725 2100);
DISPLAY 1.021277 (-1725 2100);
PAINT WHITE (-1725 2100);
QUIT
